G04 ================== begin FILE IDENTIFICATION RECORD ==================*
G04 Layout Name:  D:/<user>/Wistron_project/16315-1/gbr/16315-1.brd*
G04 Film Name:    L2GND*
G04 File Format:  Gerber RS274X*
G04 File Origin:  Cadence Allegro 16.5-S056*
G04 Origin Date:  Fri Jun 09 15:31:16 2017*
G04 *
G04 Layer:  VIA CLASS/L2GND*
G04 Layer:  PIN/L2GND*
G04 Layer:  ETCH/L2GND*
G04 Layer:  DRAWING FORMAT/LAYER_PCB_STORY*
G04 Layer:  DRAWING FORMAT/LAYER_L2GND*
G04 *
G04 Offset:    (0.00 0.00)*
G04 Mirror:    No*
G04 Mode:      Negative*
G04 Rotation:  0*
G04 FullContactRelief:  No*
G04 UndefLineWidth:     6.00*
G04 ================== end FILE IDENTIFICATION RECORD ====================*
%FSLAX35Y35*MOIN*%
%IR0*IPPOS*OFA0.00000B0.00000*MIA0B0*SFA1.00000B1.00000*%
%ADD24C,.03*%
%ADD44C,.04*%
%ADD14C,.032*%
%ADD42C,.052*%
%ADD33C,.043*%
%ADD22C,.036*%
%ADD20C,.081*%
%ADD32C,.047*%
%ADD19C,.065*%
%ADD38C,.057*%
%ADD43C,.058*%
%AMMACRO31*
4,1,15,.00398,.00044,
.003999,.000208,
.004004,-.000025,
.003996,-.000258,
.00398,-.00044,
.00483,-.00129,
.004897,-.001007,
.004947,-.000721,
.004981,-.000432,
.004997,-.000141,
.004997,.000149,
.00498,.00044,
.004946,.000729,
.004895,.001015,
.00483,.00129,
.00398,.00044,
90.*
4,1,15,.00044,-.00398,
.000208,-.003999,
-.000025,-.004004,
-.000258,-.003996,
-.00044,-.00398,
-.00129,-.00483,
-.001007,-.004897,
-.000721,-.004947,
-.000432,-.004981,
-.000141,-.004997,
.000149,-.004997,
.00044,-.00498,
.000729,-.004946,
.001015,-.004895,
.00129,-.00483,
.00044,-.00398,
90.*
4,1,15,-.00398,-.00044,
-.003999,-.000208,
-.004004,.000025,
-.003996,.000258,
-.00398,.00044,
-.00483,.00129,
-.004897,.001007,
-.004947,.000721,
-.004981,.000432,
-.004997,.000141,
-.004997,-.000149,
-.00498,-.00044,
-.004946,-.000729,
-.004895,-.001015,
-.00483,-.00129,
-.00398,-.00044,
90.*
4,1,15,-.00044,.00398,
-.000208,.003999,
.000025,.004004,
.000258,.003996,
.00044,.00398,
.00129,.00483,
.001007,.004897,
.000721,.004947,
.000432,.004981,
.000141,.004997,
-.000149,.004997,
-.00044,.00498,
-.000729,.004946,
-.001015,.004895,
-.00129,.00483,
-.00044,.00398,
90.*
%
%ADD31MACRO31*%
%AMMACRO28*
4,1,15,-.00398,.00044,
-.003999,.000208,
-.004004,-.000025,
-.003996,-.000258,
-.00398,-.00044,
-.00483,-.00129,
-.004897,-.001007,
-.004947,-.000721,
-.004981,-.000432,
-.004997,-.000141,
-.004997,.000149,
-.00498,.00044,
-.004946,.000729,
-.004895,.001015,
-.00483,.00129,
-.00398,.00044,
90.*
4,1,15,-.00044,-.00398,
-.000208,-.003999,
.000025,-.004004,
.000258,-.003996,
.00044,-.00398,
.00129,-.00483,
.001007,-.004897,
.000721,-.004947,
.000432,-.004981,
.000141,-.004997,
-.000149,-.004997,
-.00044,-.00498,
-.000729,-.004946,
-.001015,-.004895,
-.00129,-.00483,
-.00044,-.00398,
90.*
4,1,15,.00398,-.00044,
.003999,-.000208,
.004004,.000025,
.003996,.000258,
.00398,.00044,
.00483,.00129,
.004897,.001007,
.004947,.000721,
.004981,.000432,
.004997,.000141,
.004997,-.000149,
.00498,-.00044,
.004946,-.000729,
.004895,-.001015,
.00483,-.00129,
.00398,-.00044,
90.*
4,1,15,.00044,.00398,
.000208,.003999,
-.000025,.004004,
-.000258,.003996,
-.00044,.00398,
-.00129,.00483,
-.001007,.004897,
-.000721,.004947,
-.000432,.004981,
-.000141,.004997,
.000149,.004997,
.00044,.00498,
.000729,.004946,
.001015,.004895,
.00129,.00483,
.00044,.00398,
90.*
%
%ADD28MACRO28*%
%AMMACRO11*
4,1,15,.00398,.00044,
.003999,.000208,
.004004,-.000025,
.003996,-.000258,
.00398,-.00044,
.00483,-.00129,
.004897,-.001007,
.004947,-.000721,
.004981,-.000432,
.004997,-.000141,
.004997,.000149,
.00498,.00044,
.004946,.000729,
.004895,.001015,
.00483,.00129,
.00398,.00044,
0.0*
4,1,15,.00044,-.00398,
.000208,-.003999,
-.000025,-.004004,
-.000258,-.003996,
-.00044,-.00398,
-.00129,-.00483,
-.001007,-.004897,
-.000721,-.004947,
-.000432,-.004981,
-.000141,-.004997,
.000149,-.004997,
.00044,-.00498,
.000729,-.004946,
.001015,-.004895,
.00129,-.00483,
.00044,-.00398,
0.0*
4,1,15,-.00398,-.00044,
-.003999,-.000208,
-.004004,.000025,
-.003996,.000258,
-.00398,.00044,
-.00483,.00129,
-.004897,.001007,
-.004947,.000721,
-.004981,.000432,
-.004997,.000141,
-.004997,-.000149,
-.00498,-.00044,
-.004946,-.000729,
-.004895,-.001015,
-.00483,-.00129,
-.00398,-.00044,
0.0*
4,1,15,-.00044,.00398,
-.000208,.003999,
.000025,.004004,
.000258,.003996,
.00044,.00398,
.00129,.00483,
.001007,.004897,
.000721,.004947,
.000432,.004981,
.000141,.004997,
-.000149,.004997,
-.00044,.00498,
-.000729,.004946,
-.001015,.004895,
-.00129,.00483,
-.00044,.00398,
0.0*
%
%ADD11MACRO11*%
%AMMACRO37*
4,1,47,.19499,.0719,
.215281,.036007,
.229031,-.002865,
.235822,-.043533,
.235448,-.084763,
.22792,-.125302,
.213467,-.163917,
.192528,-.199436,
.16574,-.23078,
.133915,-.256995,
.098022,-.277286,
.059151,-.291036,
.018482,-.297827,
-.022748,-.297453,
-.063286,-.289925,
-.101902,-.275472,
-.137421,-.254533,
-.168764,-.227745,
-.19498,-.19592,
-.215271,-.160027,
-.229021,-.121156,
-.235812,-.080487,
-.235438,-.039257,
-.22791,.001281,
-.213457,.039897,
-.19498,.0719,
-.17079,.109417,
-.148822,.148276,
-.129151,.188348,
-.11538,.22052,
-.105587,.239854,
-.092586,.257193,
-.076771,.272012,
-.058623,.283859,
-.038693,.292375,
-.017588,.297301,
.004052,.298487,
.025569,.295897,
.04631,.28961,
.065644,.279817,
.082983,.266816,
.097802,.251001,
.109649,.232853,
.1154,.22052,
.133222,.179593,
.153393,.139771,
.175846,.101189,
.19499,.0719,
0.0*
%
%ADD37MACRO37*%
%AMMACRO23*
4,1,15,-.00398,.00044,
-.003999,.000208,
-.004004,-.000025,
-.003996,-.000258,
-.00398,-.00044,
-.00483,-.00129,
-.004897,-.001007,
-.004947,-.000721,
-.004981,-.000432,
-.004997,-.000141,
-.004997,.000149,
-.00498,.00044,
-.004946,.000729,
-.004895,.001015,
-.00483,.00129,
-.00398,.00044,
0.0*
4,1,15,-.00044,-.00398,
-.000208,-.003999,
.000025,-.004004,
.000258,-.003996,
.00044,-.00398,
.00129,-.00483,
.001007,-.004897,
.000721,-.004947,
.000432,-.004981,
.000141,-.004997,
-.000149,-.004997,
-.00044,-.00498,
-.000729,-.004946,
-.001015,-.004895,
-.00129,-.00483,
-.00044,-.00398,
0.0*
4,1,15,.00398,-.00044,
.003999,-.000208,
.004004,.000025,
.003996,.000258,
.00398,.00044,
.00483,.00129,
.004897,.001007,
.004947,.000721,
.004981,.000432,
.004997,.000141,
.004997,-.000149,
.00498,-.00044,
.004946,-.000729,
.004895,-.001015,
.00483,-.00129,
.00398,-.00044,
0.0*
4,1,15,.00044,.00398,
.000208,.003999,
-.000025,.004004,
-.000258,.003996,
-.00044,.00398,
-.00129,.00483,
-.001007,.004897,
-.000721,.004947,
-.000432,.004981,
-.000141,.004997,
.000149,.004997,
.00044,.00498,
.000729,.004946,
.001015,.004895,
.00129,.00483,
.00044,.00398,
0.0*
%
%ADD23MACRO23*%
%ADD39C,.121*%
%ADD34C,.122*%
%ADD15C,.114*%
%ADD18C,.115*%
%ADD12O,.206X.285*%
%ADD35C,.125*%
%ADD10C,.206*%
%ADD36C,.432*%
%ADD26C,.18*%
%ADD13C,.208*%
%ADD40O,.159X.237*%
%ADD27C,.139*%
%ADD17C,.265*%
%ADD41C,.159*%
%ADD45C,.178*%
%AMMACRO25*
4,1,15,.00398,.00044,
.003999,.000208,
.004004,-.000025,
.003996,-.000258,
.00398,-.00044,
.00483,-.00129,
.004897,-.001007,
.004947,-.000721,
.004981,-.000432,
.004997,-.000141,
.004997,.000149,
.00498,.00044,
.004946,.000729,
.004895,.001015,
.00483,.00129,
.00398,.00044,
270.*
4,1,15,.00044,-.00398,
.000208,-.003999,
-.000025,-.004004,
-.000258,-.003996,
-.00044,-.00398,
-.00129,-.00483,
-.001007,-.004897,
-.000721,-.004947,
-.000432,-.004981,
-.000141,-.004997,
.000149,-.004997,
.00044,-.00498,
.000729,-.004946,
.001015,-.004895,
.00129,-.00483,
.00044,-.00398,
270.*
4,1,15,-.00398,-.00044,
-.003999,-.000208,
-.004004,.000025,
-.003996,.000258,
-.00398,.00044,
-.00483,.00129,
-.004897,.001007,
-.004947,.000721,
-.004981,.000432,
-.004997,.000141,
-.004997,-.000149,
-.00498,-.00044,
-.004946,-.000729,
-.004895,-.001015,
-.00483,-.00129,
-.00398,-.00044,
270.*
4,1,15,-.00044,.00398,
-.000208,.003999,
.000025,.004004,
.000258,.003996,
.00044,.00398,
.00129,.00483,
.001007,.004897,
.000721,.004947,
.000432,.004981,
.000141,.004997,
-.000149,.004997,
-.00044,.00498,
-.000729,.004946,
-.001015,.004895,
-.00129,.00483,
-.00044,.00398,
270.*
%
%ADD25MACRO25*%
%AMMACRO16*
4,1,15,.00398,.00044,
.003999,.000208,
.004004,-.000025,
.003996,-.000258,
.00398,-.00044,
.00483,-.00129,
.004897,-.001007,
.004947,-.000721,
.004981,-.000432,
.004997,-.000141,
.004997,.000149,
.00498,.00044,
.004946,.000729,
.004895,.001015,
.00483,.00129,
.00398,.00044,
180.*
4,1,15,.00044,-.00398,
.000208,-.003999,
-.000025,-.004004,
-.000258,-.003996,
-.00044,-.00398,
-.00129,-.00483,
-.001007,-.004897,
-.000721,-.004947,
-.000432,-.004981,
-.000141,-.004997,
.000149,-.004997,
.00044,-.00498,
.000729,-.004946,
.001015,-.004895,
.00129,-.00483,
.00044,-.00398,
180.*
4,1,15,-.00398,-.00044,
-.003999,-.000208,
-.004004,.000025,
-.003996,.000258,
-.00398,.00044,
-.00483,.00129,
-.004897,.001007,
-.004947,.000721,
-.004981,.000432,
-.004997,.000141,
-.004997,-.000149,
-.00498,-.00044,
-.004946,-.000729,
-.004895,-.001015,
-.00483,-.00129,
-.00398,-.00044,
180.*
4,1,15,-.00044,.00398,
-.000208,.003999,
.000025,.004004,
.000258,.003996,
.00044,.00398,
.00129,.00483,
.001007,.004897,
.000721,.004947,
.000432,.004981,
.000141,.004997,
-.000149,.004997,
-.00044,.00498,
-.000729,.004946,
-.001015,.004895,
-.00129,.00483,
-.00044,.00398,
180.*
%
%ADD16MACRO16*%
%AMMACRO30*
4,1,15,-.00398,.00044,
-.003999,.000208,
-.004004,-.000025,
-.003996,-.000258,
-.00398,-.00044,
-.00483,-.00129,
-.004897,-.001007,
-.004947,-.000721,
-.004981,-.000432,
-.004997,-.000141,
-.004997,.000149,
-.00498,.00044,
-.004946,.000729,
-.004895,.001015,
-.00483,.00129,
-.00398,.00044,
270.*
4,1,15,-.00044,-.00398,
-.000208,-.003999,
.000025,-.004004,
.000258,-.003996,
.00044,-.00398,
.00129,-.00483,
.001007,-.004897,
.000721,-.004947,
.000432,-.004981,
.000141,-.004997,
-.000149,-.004997,
-.00044,-.00498,
-.000729,-.004946,
-.001015,-.004895,
-.00129,-.00483,
-.00044,-.00398,
270.*
4,1,15,.00398,-.00044,
.003999,-.000208,
.004004,.000025,
.003996,.000258,
.00398,.00044,
.00483,.00129,
.004897,.001007,
.004947,.000721,
.004981,.000432,
.004997,.000141,
.004997,-.000149,
.00498,-.00044,
.004946,-.000729,
.004895,-.001015,
.00483,-.00129,
.00398,-.00044,
270.*
4,1,15,.00044,.00398,
.000208,.003999,
-.000025,.004004,
-.000258,.003996,
-.00044,.00398,
-.00129,.00483,
-.001007,.004897,
-.000721,.004947,
-.000432,.004981,
-.000141,.004997,
.000149,.004997,
.00044,.00498,
.000729,.004946,
.001015,.004895,
.00129,.00483,
.00044,.00398,
270.*
%
%ADD30MACRO30*%
%AMMACRO29*
4,1,15,-.00398,.00044,
-.003999,.000208,
-.004004,-.000025,
-.003996,-.000258,
-.00398,-.00044,
-.00483,-.00129,
-.004897,-.001007,
-.004947,-.000721,
-.004981,-.000432,
-.004997,-.000141,
-.004997,.000149,
-.00498,.00044,
-.004946,.000729,
-.004895,.001015,
-.00483,.00129,
-.00398,.00044,
180.*
4,1,15,-.00044,-.00398,
-.000208,-.003999,
.000025,-.004004,
.000258,-.003996,
.00044,-.00398,
.00129,-.00483,
.001007,-.004897,
.000721,-.004947,
.000432,-.004981,
.000141,-.004997,
-.000149,-.004997,
-.00044,-.00498,
-.000729,-.004946,
-.001015,-.004895,
-.00129,-.00483,
-.00044,-.00398,
180.*
4,1,15,.00398,-.00044,
.003999,-.000208,
.004004,.000025,
.003996,.000258,
.00398,.00044,
.00483,.00129,
.004897,.001007,
.004947,.000721,
.004981,.000432,
.004997,.000141,
.004997,-.000149,
.00498,-.00044,
.004946,-.000729,
.004895,-.001015,
.00483,-.00129,
.00398,-.00044,
180.*
4,1,15,.00044,.00398,
.000208,.003999,
-.000025,.004004,
-.000258,.003996,
-.00044,.00398,
-.00129,.00483,
-.001007,.004897,
-.000721,.004947,
-.000432,.004981,
-.000141,.004997,
.000149,.004997,
.00044,.00498,
.000729,.004946,
.001015,.004895,
.00129,.00483,
.00044,.00398,
180.*
%
%ADD29MACRO29*%
%ADD46C,.02*%
%ADD47C,.006*%
%ADD59C,.06104*%
%ADD54R,.09302X.12604*%
%ADD55R,.09304X.12604*%
%ADD60C,.07704*%
%ADD61C,.11004*%
%ADD58C,.11104*%
%ADD65C,.11704*%
%ADD62C,.13504*%
%ADD64C,.11804*%
%ADD57C,.37504*%
%ADD67C,.29531*%
%ADD56C,.29532*%
%ADD66C,.29533*%
%ADD63C,.23629*%
%ADD48O,.55202X.78802*%
%ADD51O,.09834X.04322*%
%ADD49O,.55204X.78804*%
%ADD53O,.09854X.04342*%
%ADD50O,.09836X.04324*%
%ADD52O,.09856X.04344*%
G75*
%LPD*%
G75*
G36*
G01X-6000Y-158756D02*
X1940843D01*
Y1664268D01*
X-6000D01*
Y-158756D01*
G37*
%LPC*%
G75*
G36*
G01X1216535Y1655264D02*
G02X1217468Y1654331I0J-933D01*
G01Y1476378D01*
G02X1216535Y1475445I-933J0D01*
G01X1168110D01*
G03X1161169Y1468504I0J-6941D01*
G01Y1378740D01*
G03X1168110Y1371799I6941J0D01*
G01X1930906D01*
G02X1931839Y1370866I0J-933D01*
G01Y3937D01*
G02X1930906Y3004I-933J0D01*
G01X1562992D01*
G02X1562059Y3937I0J933D01*
G01Y55118D01*
G03X1555118Y62059I-6941J0D01*
G01X1374016D01*
G03X1367075Y55118I0J-6941D01*
G01Y3937D01*
G02X1366142Y3004I-933J0D01*
G01X1185039D01*
G03X1178098Y-3937I0J-6941D01*
G01Y-148819D01*
G02X1177165Y-149752I-933J0D01*
G01X870079D01*
G02X869146Y-148819I0J933D01*
G01Y-11811D01*
G03X862205Y-4870I-6941J0D01*
G01X791339D01*
G02X790406Y-3937I0J933D01*
G03X783465Y3004I-6941J0D01*
G01X594488D01*
G02X593555Y3937I0J933D01*
G01Y55118D01*
G03X586614Y62059I-6941J0D01*
G01X405512D01*
G03X398571Y55118I0J-6941D01*
G01Y3937D01*
G02X397638Y3004I-933J0D01*
G01X3937D01*
G02X3004Y3937I0J933D01*
G01Y12071D01*
G02X3714Y12323I400J0D01*
G03X29922Y21653I11443J9331D01*
G01Y21654D01*
G03X3714Y30984I-14765J0D01*
G02X3004Y31236I-310J253D01*
G01Y464768D01*
G02X3713Y465022I400J0D01*
G03X12310Y459884I11444J9387D01*
G03X18004I2847J10575D01*
G03Y488934I-2847J14525D01*
G03X12310I-2847J-10575D01*
G03X3713Y483796I2847J-14525D01*
G02X3004Y484050I-309J254D01*
G01Y1370866D01*
G02X3937Y1371799I933J0D01*
G01X746850D01*
G03X753791Y1378740I0J6941D01*
G01Y1464567D01*
G02X754724Y1465500I933J0D01*
G01X783465D01*
G03X790406Y1472441I0J6941D01*
G01Y1654331D01*
G02X791339Y1655264I933J0D01*
G01X1216535D01*
G37*
%LPD*%
G75*
G36*
G01X1124313Y534842D02*
X1124318Y534833D01*
X1116440Y530894D01*
X1116437Y530899D01*
X1116339Y530857D01*
G02X1113786Y535977I-1183J2607D01*
G01X1113872Y536027D01*
X1113870Y536032D01*
X1121747Y539971D01*
X1121753Y539965D01*
X1121814Y539992D01*
G02X1124313Y534842I1217J-2591D01*
G37*
G36*
G01X945676Y535977D02*
X945762Y536027D01*
X945760Y536032D01*
X953638Y539971D01*
X953641Y539966D01*
X953739Y540008D01*
G02X956203Y534842I1182J-2607D01*
G01X956208Y534833D01*
X948331Y530894D01*
X948325Y530900D01*
X948264Y530873D01*
G02X945676Y535977I-1217J2591D01*
G37*
G36*
G01X1897508Y459879D02*
G02X1891860I-2824J10580D01*
G02Y488939I2824J14530D01*
G02X1897508I2824J-10580D01*
G02Y459879I-2824J-14530D01*
G37*
G36*
G01X945676Y425741D02*
X945762Y425791D01*
X945760Y425796D01*
X953638Y429735D01*
X953641Y429730D01*
X953739Y429772D01*
G02X956203Y424606I1182J-2607D01*
G01X956208Y424597D01*
X948331Y420658D01*
X948325Y420664D01*
X948264Y420637D01*
G02X945676Y425741I-1217J2591D01*
G37*
G36*
G01X907745Y-40121D02*
G02X902097I-2824J10580D01*
G02Y-11061I2824J14530D01*
G02X907745I2824J-10580D01*
G02Y-40121I-2824J-14530D01*
G37*
G36*
G01X1519850Y558011D02*
Y535489D01*
X1500711Y516350D01*
X1472407D01*
X1464911Y508854D01*
X1413785D01*
X1409550Y513089D01*
Y577811D01*
X1429389Y597650D01*
X1480211D01*
X1519850Y558011D01*
G37*
G36*
G01X1885540Y1077004D02*
Y1077804D01*
G02X1885741Y1078006I201J1D01*
G01X1888941D01*
G02X1889142Y1077804I-1J-202D01*
G01Y1077004D01*
G02X1888941Y1076802I-201J-1D01*
G01X1885741D01*
G02X1885540Y1077004I1J202D01*
G37*
G36*
G01Y1079204D02*
Y1080004D01*
G02X1885741Y1080206I201J1D01*
G01X1888941D01*
G02X1889142Y1080004I-1J-202D01*
G01Y1079204D01*
G02X1888941Y1079002I-201J-1D01*
G01X1885741D01*
G02X1885540Y1079204I1J202D01*
G37*
G36*
G01Y624248D02*
Y625048D01*
G02X1885741Y625250I201J1D01*
G01X1888941D01*
G02X1889142Y625048I-1J-202D01*
G01Y624248D01*
G02X1888941Y624046I-201J-1D01*
G01X1885741D01*
G02X1885540Y624248I1J202D01*
G37*
G36*
G01Y626448D02*
Y627248D01*
G02X1885741Y627450I201J1D01*
G01X1888941D01*
G02X1889142Y627248I-1J-202D01*
G01Y626448D01*
G02X1888941Y626246I-201J-1D01*
G01X1885741D01*
G02X1885540Y626448I1J202D01*
G37*
G36*
G01Y171492D02*
Y172292D01*
G02X1885741Y172494I201J1D01*
G01X1888941D01*
G02X1889142Y172292I-1J-202D01*
G01Y171492D01*
G02X1888941Y171290I-201J-1D01*
G01X1885741D01*
G02X1885540Y171492I1J202D01*
G37*
G36*
G01Y173692D02*
Y174492D01*
G02X1885741Y174694I201J1D01*
G01X1888941D01*
G02X1889142Y174492I-1J-202D01*
G01Y173692D01*
G02X1888941Y173490I-201J-1D01*
G01X1885741D01*
G02X1885540Y173692I1J202D01*
G37*
G36*
G01X1761326Y1077004D02*
Y1077804D01*
G02X1761528Y1078006I202J0D01*
G01X1764728D01*
G02X1764930Y1077804I0J-202D01*
G01Y1077004D01*
G02X1764728Y1076802I-202J0D01*
G01X1761528D01*
G02X1761326Y1077004I0J202D01*
G37*
G36*
G01Y1079204D02*
Y1080004D01*
G02X1761528Y1080206I202J0D01*
G01X1764728D01*
G02X1764930Y1080004I0J-202D01*
G01Y1079204D01*
G02X1764728Y1079002I-202J0D01*
G01X1761528D01*
G02X1761326Y1079204I0J202D01*
G37*
G36*
G01X1736326Y624248D02*
Y625048D01*
G02X1736528Y625250I202J0D01*
G01X1739728D01*
G02X1739930Y625048I0J-202D01*
G01Y624248D01*
G02X1739728Y624046I-202J0D01*
G01X1736528D01*
G02X1736326Y624248I0J202D01*
G37*
G36*
G01Y626448D02*
Y627248D01*
G02X1736528Y627450I202J0D01*
G01X1739728D01*
G02X1739930Y627248I0J-202D01*
G01Y626448D01*
G02X1739728Y626246I-202J0D01*
G01X1736528D01*
G02X1736326Y626448I0J202D01*
G37*
G36*
G01X1761326Y171492D02*
Y172292D01*
G02X1761528Y172494I202J0D01*
G01X1764728D01*
G02X1764930Y172292I0J-202D01*
G01Y171492D01*
G02X1764728Y171290I-202J0D01*
G01X1761528D01*
G02X1761326Y171492I0J202D01*
G37*
G36*
G01Y173692D02*
Y174492D01*
G02X1761528Y174694I202J0D01*
G01X1764728D01*
G02X1764930Y174492I0J-202D01*
G01Y173692D01*
G02X1764728Y173490I-202J0D01*
G01X1761528D01*
G02X1761326Y173692I0J202D01*
G37*
G36*
G01X1637114Y1077004D02*
Y1077804D01*
G02X1637316Y1078006I202J0D01*
G01X1640516D01*
G02X1640718Y1077804I0J-202D01*
G01Y1077004D01*
G02X1640516Y1076802I-202J0D01*
G01X1637316D01*
G02X1637114Y1077004I0J202D01*
G37*
G36*
G01Y1079204D02*
Y1080004D01*
G02X1637316Y1080206I202J0D01*
G01X1640516D01*
G02X1640718Y1080004I0J-202D01*
G01Y1079204D01*
G02X1640516Y1079002I-202J0D01*
G01X1637316D01*
G02X1637114Y1079204I0J202D01*
G37*
G36*
G01Y624248D02*
Y625048D01*
G02X1637316Y625250I202J0D01*
G01X1640516D01*
G02X1640718Y625048I0J-202D01*
G01Y624248D01*
G02X1640516Y624046I-202J0D01*
G01X1637316D01*
G02X1637114Y624248I0J202D01*
G37*
G36*
G01Y626448D02*
Y627248D01*
G02X1637316Y627450I202J0D01*
G01X1640516D01*
G02X1640718Y627248I0J-202D01*
G01Y626448D01*
G02X1640516Y626246I-202J0D01*
G01X1637316D01*
G02X1637114Y626448I0J202D01*
G37*
G36*
G01Y171492D02*
Y172292D01*
G02X1637316Y172494I202J0D01*
G01X1640516D01*
G02X1640718Y172292I0J-202D01*
G01Y171492D01*
G02X1640516Y171290I-202J0D01*
G01X1637316D01*
G02X1637114Y171492I0J202D01*
G37*
G36*
G01Y173692D02*
Y174492D01*
G02X1637316Y174694I202J0D01*
G01X1640516D01*
G02X1640718Y174492I0J-202D01*
G01Y173692D01*
G02X1640516Y173490I-202J0D01*
G01X1637316D01*
G02X1637114Y173692I0J202D01*
G37*
G36*
G01X1535036Y77756D02*
Y72244D01*
G02X1530712Y72245I-2162J1D01*
G01Y77756D01*
G02X1535036I2162J0D01*
G37*
G36*
G01Y91930D02*
Y86417D01*
G02X1530712Y86418I-2162J1D01*
G01Y91930D01*
G02X1535036I2162J0D01*
G37*
G36*
G01X1527948Y87993D02*
Y82480D01*
G02X1523626Y82481I-2161J1D01*
G01Y87993D01*
G02X1527948I2161J0D01*
G37*
G36*
G01X1535036Y120276D02*
Y114763D01*
G02X1530712Y114764I-2162J1D01*
G01Y120276D01*
G02X1535036I2162J0D01*
G37*
G36*
G01X1527948Y73819D02*
Y68306D01*
G02X1523626Y68307I-2161J1D01*
G01Y73819D01*
G02X1527948I2161J0D01*
G37*
G36*
G01X1512902Y1079204D02*
Y1080004D01*
G02X1513103Y1080206I201J1D01*
G01X1516303D01*
G02X1516504Y1080004I-1J-202D01*
G01Y1079204D01*
G02X1516303Y1079002I-201J-1D01*
G01X1513103D01*
G02X1512902Y1079204I1J202D01*
G37*
G36*
G01Y1077004D02*
Y1077804D01*
G02X1513103Y1078006I201J1D01*
G01X1516303D01*
G02X1516504Y1077804I-1J-202D01*
G01Y1077004D01*
G02X1516303Y1076802I-201J-1D01*
G01X1513103D01*
G02X1512902Y1077004I1J202D01*
G37*
G36*
G01Y624248D02*
Y625048D01*
G02X1513103Y625250I201J1D01*
G01X1516303D01*
G02X1516504Y625048I-1J-202D01*
G01Y624248D01*
G02X1516303Y624046I-201J-1D01*
G01X1513103D01*
G02X1512902Y624248I1J202D01*
G37*
G36*
G01Y626448D02*
Y627248D01*
G02X1513103Y627450I201J1D01*
G01X1516303D01*
G02X1516504Y627248I-1J-202D01*
G01Y626448D01*
G02X1516303Y626246I-201J-1D01*
G01X1513103D01*
G02X1512902Y626448I1J202D01*
G37*
G36*
G01Y171492D02*
Y172292D01*
G02X1513103Y172494I201J1D01*
G01X1516303D01*
G02X1516504Y172292I-1J-202D01*
G01Y171492D01*
G02X1516303Y171290I-201J-1D01*
G01X1513103D01*
G02X1512902Y171492I1J202D01*
G37*
G36*
G01Y173692D02*
Y174492D01*
G02X1513103Y174694I201J1D01*
G01X1516303D01*
G02X1516504Y174492I-1J-202D01*
G01Y173692D01*
G02X1516303Y173490I-201J-1D01*
G01X1513103D01*
G02X1512902Y173692I1J202D01*
G37*
G36*
G01X1520862Y77756D02*
Y72244D01*
G02X1516540Y72245I-2161J1D01*
G01Y77756D01*
G02X1520862I2161J0D01*
G37*
G36*
G01X1506690D02*
Y72244D01*
G02X1502366Y72245I-2162J1D01*
G01Y77756D01*
G02X1506690I2162J0D01*
G37*
G36*
G01X1492516D02*
Y72244D01*
G02X1488192Y72245I-2162J1D01*
G01Y77756D01*
G02X1492516I2162J0D01*
G37*
G36*
G01X1520862Y91930D02*
Y86417D01*
G02X1516540Y86418I-2161J1D01*
G01Y91930D01*
G02X1520862I2161J0D01*
G37*
G36*
G01X1513776Y87993D02*
Y82480D01*
G02X1509452Y82481I-2162J1D01*
G01Y87993D01*
G02X1513776I2162J0D01*
G37*
G36*
G01X1506690Y91930D02*
Y86417D01*
G02X1502366Y86418I-2162J1D01*
G01Y91930D01*
G02X1506690I2162J0D01*
G37*
G36*
G01X1499602Y87993D02*
Y82480D01*
G02X1495280Y82481I-2161J1D01*
G01Y87993D01*
G02X1499602I2161J0D01*
G37*
G36*
G01X1492516Y91930D02*
Y86417D01*
G02X1488192Y86418I-2162J1D01*
G01Y91930D01*
G02X1492516I2162J0D01*
G37*
G36*
G01X1485430Y87993D02*
Y82480D01*
G02X1481106Y82481I-2162J1D01*
G01Y87993D01*
G02X1485430I2162J0D01*
G37*
G36*
G01X1506700Y120276D02*
Y114763D01*
G02X1502356Y114764I-2172J1D01*
G01Y120276D01*
G02X1506700I2172J0D01*
G37*
G36*
G01X1513776Y73819D02*
Y68306D01*
G02X1509452Y68307I-2162J1D01*
G01Y73819D01*
G02X1513776I2162J0D01*
G37*
G36*
G01X1499602D02*
Y68306D01*
G02X1495280Y68307I-2161J1D01*
G01Y73819D01*
G02X1499602I2161J0D01*
G37*
G36*
G01X1485430D02*
Y68306D01*
G02X1481106Y68307I-2162J1D01*
G01Y73819D01*
G02X1485430I2162J0D01*
G37*
G36*
G01X1449996Y77756D02*
Y72244D01*
G02X1445674Y72245I-2161J1D01*
G01Y77756D01*
G02X1449996I2161J0D01*
G37*
G36*
G01X1435822D02*
Y72244D01*
G02X1431500Y72245I-2161J1D01*
G01Y77756D01*
G02X1435822I2161J0D01*
G37*
G36*
G01X1449996Y91930D02*
Y86417D01*
G02X1445674Y86418I-2161J1D01*
G01Y91930D01*
G02X1449996I2161J0D01*
G37*
G36*
G01X1442910Y87993D02*
Y82480D01*
G02X1438586Y82481I-2162J1D01*
G01Y87993D01*
G02X1442910I2162J0D01*
G37*
G36*
G01X1435822Y91930D02*
Y86417D01*
G02X1431500Y86418I-2161J1D01*
G01Y91930D01*
G02X1435822I2161J0D01*
G37*
G36*
G01X1445664Y114764D02*
Y120277D01*
G02X1450006Y120276I2171J-1D01*
G01Y114764D01*
G02X1445664I-2171J0D01*
G37*
G36*
G01X1442910Y73819D02*
Y68306D01*
G02X1438586Y68307I-2162J1D01*
G01Y73819D01*
G02X1442910I2162J0D01*
G37*
G36*
G01X1388690Y1077004D02*
Y1077804D01*
G02X1388891Y1078006I201J1D01*
G01X1392091D01*
G02X1392292Y1077804I-1J-202D01*
G01Y1077004D01*
G02X1392091Y1076802I-201J-1D01*
G01X1388891D01*
G02X1388690Y1077004I1J202D01*
G37*
G36*
G01Y1079204D02*
Y1080004D01*
G02X1388891Y1080206I201J1D01*
G01X1392091D01*
G02X1392292Y1080004I-1J-202D01*
G01Y1079204D01*
G02X1392091Y1079002I-201J-1D01*
G01X1388891D01*
G02X1388690Y1079204I1J202D01*
G37*
G36*
G01Y624248D02*
Y625048D01*
G02X1388891Y625250I201J1D01*
G01X1392091D01*
G02X1392292Y625048I-1J-202D01*
G01Y624248D01*
G02X1392091Y624046I-201J-1D01*
G01X1388891D01*
G02X1388690Y624248I1J202D01*
G37*
G36*
G01Y626448D02*
Y627248D01*
G02X1388891Y627450I201J1D01*
G01X1392091D01*
G02X1392292Y627248I-1J-202D01*
G01Y626448D01*
G02X1392091Y626246I-201J-1D01*
G01X1388891D01*
G02X1388690Y626448I1J202D01*
G37*
G36*
G01X1404234Y190242D02*
Y185741D01*
G02X1401192Y185742I-1521J1D01*
G01Y190242D01*
G02X1404234I1521J0D01*
G37*
G36*
G01X1385463Y166302D02*
X1380962D01*
G02X1380963Y169344I1J1521D01*
G01X1385463D01*
G02Y166302I0J-1521D01*
G37*
G36*
G01X1388690Y171492D02*
Y172292D01*
G02X1388891Y172494I201J1D01*
G01X1392091D01*
G02X1392292Y172292I-1J-202D01*
G01Y171492D01*
G02X1392091Y171290I-201J-1D01*
G01X1388891D01*
G02X1388690Y171492I1J202D01*
G37*
G36*
G01Y173692D02*
Y174492D01*
G02X1388891Y174694I201J1D01*
G01X1392091D01*
G02X1392292Y174492I-1J-202D01*
G01Y173692D01*
G02X1392091Y173490I-201J-1D01*
G01X1388891D01*
G02X1388690Y173692I1J202D01*
G37*
G36*
G01X1421650Y77756D02*
Y72244D01*
G02X1417326Y72245I-2162J1D01*
G01Y77756D01*
G02X1421650I2162J0D01*
G37*
G36*
G01X1407476D02*
Y72244D01*
G02X1403154Y72245I-2161J1D01*
G01Y77756D01*
G02X1407476I2161J0D01*
G37*
G36*
G01X1428736Y87993D02*
Y82480D01*
G02X1424414Y82481I-2161J1D01*
G01Y87993D01*
G02X1428736I2161J0D01*
G37*
G36*
G01X1421650Y91930D02*
Y86417D01*
G02X1417326Y86418I-2162J1D01*
G01Y91930D01*
G02X1421650I2162J0D01*
G37*
G36*
G01X1414564Y87993D02*
Y82480D01*
G02X1410240Y82481I-2162J1D01*
G01Y87993D01*
G02X1414564I2162J0D01*
G37*
G36*
G01X1407476Y91930D02*
Y86417D01*
G02X1403154Y86418I-2161J1D01*
G01Y91930D01*
G02X1407476I2161J0D01*
G37*
G36*
G01X1400390Y87993D02*
Y82480D01*
G02X1396066Y82481I-2162J1D01*
G01Y87993D01*
G02X1400390I2162J0D01*
G37*
G36*
G01X1424414Y110827D02*
Y116339D01*
G02X1428736I2161J0D01*
G01Y110826D01*
G02X1424414Y110827I-2161J1D01*
G37*
G36*
G01X1428736Y73819D02*
Y68306D01*
G02X1424414Y68307I-2161J1D01*
G01Y73819D01*
G02X1428736I2161J0D01*
G37*
G36*
G01X1414564D02*
Y68306D01*
G02X1410240Y68307I-2162J1D01*
G01Y73819D01*
G02X1414564I2162J0D01*
G37*
G36*
G01X1400390D02*
Y68306D01*
G02X1396066Y68307I-2162J1D01*
G01Y73819D01*
G02X1400390I2162J0D01*
G37*
G36*
G01X1261462Y1080754D02*
Y1076253D01*
G02X1258138Y1076254I-1662J1D01*
G01Y1080754D01*
G02X1261462I1662J0D01*
G37*
G36*
G01X1264476Y1077004D02*
Y1077804D01*
G02X1264678Y1078006I202J0D01*
G01X1267878D01*
G02X1268080Y1077804I0J-202D01*
G01Y1077004D01*
G02X1267878Y1076802I-202J0D01*
G01X1264678D01*
G02X1264476Y1077004I0J202D01*
G37*
G36*
G01Y1079204D02*
Y1080004D01*
G02X1264678Y1080206I202J0D01*
G01X1267878D01*
G02X1268080Y1080004I0J-202D01*
G01Y1079204D01*
G02X1267878Y1079002I-202J0D01*
G01X1264678D01*
G02X1264476Y1079204I0J202D01*
G37*
G36*
G01Y624248D02*
Y625048D01*
G02X1264678Y625250I202J0D01*
G01X1267878D01*
G02X1268080Y625048I0J-202D01*
G01Y624248D01*
G02X1267878Y624046I-202J0D01*
G01X1264678D01*
G02X1264476Y624248I0J202D01*
G37*
G36*
G01Y626448D02*
Y627248D01*
G02X1264678Y627450I202J0D01*
G01X1267878D01*
G02X1268080Y627248I0J-202D01*
G01Y626448D01*
G02X1267878Y626246I-202J0D01*
G01X1264678D01*
G02X1264476Y626448I0J202D01*
G37*
G36*
G01Y171492D02*
Y172292D01*
G02X1264678Y172494I202J0D01*
G01X1267878D01*
G02X1268080Y172292I0J-202D01*
G01Y171492D01*
G02X1267878Y171290I-202J0D01*
G01X1264678D01*
G02X1264476Y171492I0J202D01*
G37*
G36*
G01Y173692D02*
Y174492D01*
G02X1264678Y174694I202J0D01*
G01X1267878D01*
G02X1268080Y174492I0J-202D01*
G01Y173692D01*
G02X1267878Y173490I-202J0D01*
G01X1264678D01*
G02X1264476Y173692I0J202D01*
G37*
G36*
G01X1113922Y709162D02*
X1121763Y713082D01*
X1121764Y713083D01*
G02X1124266Y708159I1267J-2454D01*
G01X1116392Y704222D01*
G02X1113922Y709162I-1235J2470D01*
G37*
G36*
G01X1104199Y696183D02*
X1104034Y696253D01*
X1104032Y696249D01*
X1096156Y700187D01*
Y700195D01*
X1096053Y700252D01*
G02X1098557Y705390I1388J2503D01*
G01X1098722Y705320D01*
X1098724Y705324D01*
X1106601Y701386D01*
X1106599Y701382D01*
X1106767Y701283D01*
G02X1104199Y696183I-1453J-2465D01*
G37*
G36*
G01X1113922Y693414D02*
X1121763Y697334D01*
X1121764Y697335D01*
G02X1124266Y692411I1267J-2454D01*
G01X1116392Y688474D01*
G02X1113922Y693414I-1235J2470D01*
G37*
G36*
G01Y677666D02*
X1121763Y681586D01*
X1121764Y681587D01*
G02X1124266Y676663I1267J-2454D01*
G01X1116392Y672726D01*
G02X1113922Y677666I-1235J2470D01*
G37*
G36*
G01Y661918D02*
X1121763Y665838D01*
X1121764Y665839D01*
G02X1124266Y660915I1267J-2454D01*
G01X1116392Y656978D01*
G02X1113922Y661918I-1235J2470D01*
G37*
G36*
G01X1104199Y680435D02*
X1104034Y680505D01*
X1104032Y680501D01*
X1096156Y684439D01*
Y684447D01*
X1096053Y684504D01*
G02X1098557Y689642I1388J2503D01*
G01X1098722Y689572D01*
X1098724Y689576D01*
X1106601Y685638D01*
X1106599Y685634D01*
X1106767Y685535D01*
G02X1104199Y680435I-1453J-2465D01*
G37*
G36*
G01Y664687D02*
X1104034Y664757D01*
X1104032Y664753D01*
X1096156Y668691D01*
Y668699D01*
X1096053Y668756D01*
G02X1098557Y673894I1388J2503D01*
G01X1098722Y673824D01*
X1098724Y673828D01*
X1106601Y669890D01*
X1106599Y669886D01*
X1106767Y669787D01*
G02X1104199Y664687I-1453J-2465D01*
G37*
G36*
G01Y648939D02*
X1104034Y649009D01*
X1104032Y649005D01*
X1096156Y652943D01*
Y652951D01*
X1096053Y653008D01*
G02X1098557Y658146I1388J2503D01*
G01X1098722Y658076D01*
X1098724Y658080D01*
X1106601Y654142D01*
X1106599Y654138D01*
X1106767Y654039D01*
G02X1104199Y648939I-1453J-2465D01*
G37*
G36*
G01X1113922Y646170D02*
X1121763Y650090D01*
X1121764Y650091D01*
G02X1124266Y645167I1267J-2454D01*
G01X1116392Y641230D01*
G02X1113922Y646170I-1235J2470D01*
G37*
G36*
G01X1124266Y629419D02*
X1116425Y625499D01*
X1116424Y625498D01*
G02X1113922Y630422I-1267J2454D01*
G01X1121796Y634359D01*
G02X1124266Y629419I1235J-2470D01*
G37*
G36*
G01X1113922Y614674D02*
X1121763Y618594D01*
X1121764Y618595D01*
G02X1124266Y613671I1267J-2454D01*
G01X1116392Y609734D01*
G02X1113922Y614674I-1235J2470D01*
G37*
G36*
G01X1104039Y601780D02*
X1096133Y605733D01*
X1096062Y605771D01*
G02X1098717Y610817I1379J2496D01*
G01X1106591Y606880D01*
G02X1104039Y601780I-1276J-2550D01*
G37*
G36*
G01Y617528D02*
X1096133Y621481D01*
X1096062Y621519D01*
G02X1098717Y626565I1379J2496D01*
G01X1106591Y622628D01*
G02X1104039Y617528I-1276J-2550D01*
G37*
G36*
G01Y633276D02*
X1096133Y637229D01*
X1096062Y637267D01*
G02X1098717Y642313I1379J2496D01*
G01X1106591Y638376D01*
G02X1104039Y633276I-1276J-2550D01*
G37*
G36*
G01X1113922Y598926D02*
X1121763Y602846D01*
X1121764Y602847D01*
G02X1124266Y597923I1267J-2454D01*
G01X1116392Y593986D01*
G02X1113922Y598926I-1235J2470D01*
G37*
G36*
G01X1104039Y586032D02*
X1096133Y589985D01*
X1096062Y590023D01*
G02X1098717Y595069I1379J2496D01*
G01X1106591Y591132D01*
G02X1104039Y586032I-1276J-2550D01*
G37*
G36*
G01X1104199Y538703D02*
X1104034Y538773D01*
X1104032Y538769D01*
X1096156Y542707D01*
Y542715D01*
X1096053Y542772D01*
G02X1098557Y547910I1388J2503D01*
G01X1098722Y547840D01*
X1098724Y547844D01*
X1106601Y543906D01*
X1106599Y543902D01*
X1106767Y543803D01*
G02X1104199Y538703I-1453J-2465D01*
G37*
G36*
G01X1104039Y507292D02*
X1096133Y511245D01*
X1096062Y511283D01*
G02X1098717Y516329I1379J2496D01*
G01X1106591Y512392D01*
G02X1104039Y507292I-1276J-2550D01*
G37*
G36*
G01X1113922Y504438D02*
X1121763Y508358D01*
X1121764Y508359D01*
G02X1124266Y503435I1267J-2454D01*
G01X1116392Y499498D01*
G02X1113922Y504438I-1235J2470D01*
G37*
G36*
G01Y488690D02*
X1121763Y492610D01*
X1121764Y492611D01*
G02X1124266Y487687I1267J-2454D01*
G01X1116392Y483750D01*
G02X1113922Y488690I-1235J2470D01*
G37*
G36*
G01Y472942D02*
X1121763Y476862D01*
X1121764Y476863D01*
G02X1124266Y471939I1267J-2454D01*
G01X1116392Y468002D01*
G02X1113922Y472942I-1235J2470D01*
G37*
G36*
G01X1104039Y460048D02*
X1096133Y464001D01*
X1096062Y464039D01*
G02X1098717Y469085I1379J2496D01*
G01X1106591Y465148D01*
G02X1104039Y460048I-1276J-2550D01*
G37*
G36*
G01Y475796D02*
X1096133Y479749D01*
X1096062Y479787D01*
G02X1098717Y484833I1379J2496D01*
G01X1106591Y480896D01*
G02X1104039Y475796I-1276J-2550D01*
G37*
G36*
G01Y491544D02*
X1096133Y495497D01*
X1096062Y495535D01*
G02X1098717Y500581I1379J2496D01*
G01X1106591Y496644D01*
G02X1104039Y491544I-1276J-2550D01*
G37*
G36*
G01X1098676Y453257D02*
X1106550Y449320D01*
G02X1104080Y444380I-1235J-2470D01*
G01X1096239Y448301D01*
X1096238D01*
G02X1098676Y453257I1203J2486D01*
G37*
G36*
G01X1113922Y457194D02*
X1121763Y461114D01*
X1121764Y461115D01*
G02X1124266Y456191I1267J-2454D01*
G01X1116392Y452254D01*
G02X1113922Y457194I-1235J2470D01*
G37*
G36*
G01X1113705Y425693D02*
X1113873Y425792D01*
X1113871Y425796D01*
X1121747Y429734D01*
X1121753Y429729D01*
X1121878Y429784D01*
G02X1124312Y424606I1153J-2619D01*
G01X1124133Y424517D01*
X1124138Y424508D01*
X1116440Y420659D01*
X1116438Y420663D01*
X1116273Y420593D01*
G02X1113705Y425693I-1115J2635D01*
G37*
G36*
G01X1113922Y330029D02*
X1121763Y333949D01*
X1121764Y333950D01*
G02X1124266Y329026I1267J-2454D01*
G01X1116392Y325089D01*
G02X1113922Y330029I-1235J2470D01*
G37*
G36*
G01X1104199Y317050D02*
X1104034Y317120D01*
X1104032Y317116D01*
X1096156Y321054D01*
Y321062D01*
X1096053Y321119D01*
G02X1098557Y326257I1388J2503D01*
G01X1098722Y326187D01*
X1098724Y326191D01*
X1106601Y322253D01*
X1106599Y322249D01*
X1106767Y322150D01*
G02X1104199Y317050I-1453J-2465D01*
G37*
G36*
G01X1113922Y314281D02*
X1121763Y318201D01*
X1121764Y318202D01*
G02X1124266Y313278I1267J-2454D01*
G01X1116392Y309341D01*
G02X1113922Y314281I-1235J2470D01*
G37*
G36*
G01X1104199Y269806D02*
X1104034Y269876D01*
X1104032Y269872D01*
X1096156Y273810D01*
Y273818D01*
X1096053Y273875D01*
G02X1098557Y279013I1388J2503D01*
G01X1098722Y278943D01*
X1098724Y278947D01*
X1106601Y275009D01*
X1106599Y275005D01*
X1106767Y274906D01*
G02X1104199Y269806I-1453J-2465D01*
G37*
G36*
G01X1113922Y282785D02*
X1121763Y286705D01*
X1121764Y286706D01*
G02X1124266Y281782I1267J-2454D01*
G01X1116392Y277845D01*
G02X1113922Y282785I-1235J2470D01*
G37*
G36*
G01Y267037D02*
X1121763Y270957D01*
X1121764Y270958D01*
G02X1124266Y266034I1267J-2454D01*
G01X1116392Y262097D01*
G02X1113922Y267037I-1235J2470D01*
G37*
G36*
G01Y298533D02*
X1121763Y302453D01*
X1121764Y302454D01*
G02X1124266Y297530I1267J-2454D01*
G01X1116392Y293593D01*
G02X1113922Y298533I-1235J2470D01*
G37*
G36*
G01X1104199Y301302D02*
X1104034Y301372D01*
X1104032Y301368D01*
X1096156Y305306D01*
Y305314D01*
X1096053Y305371D01*
G02X1098557Y310509I1388J2503D01*
G01X1098722Y310439D01*
X1098724Y310443D01*
X1106601Y306505D01*
X1106599Y306501D01*
X1106767Y306402D01*
G02X1104199Y301302I-1453J-2465D01*
G37*
G36*
G01Y285554D02*
X1104034Y285624D01*
X1104032Y285620D01*
X1096156Y289558D01*
Y289566D01*
X1096053Y289623D01*
G02X1098557Y294761I1388J2503D01*
G01X1098722Y294691D01*
X1098724Y294695D01*
X1106601Y290757D01*
X1106599Y290753D01*
X1106767Y290654D01*
G02X1104199Y285554I-1453J-2465D01*
G37*
G36*
G01Y222562D02*
X1104034Y222632D01*
X1104032Y222628D01*
X1096156Y226566D01*
Y226574D01*
X1096053Y226631D01*
G02X1098557Y231769I1388J2503D01*
G01X1098722Y231699D01*
X1098724Y231703D01*
X1106601Y227765D01*
X1106599Y227761D01*
X1106767Y227662D01*
G02X1104199Y222562I-1453J-2465D01*
G37*
G36*
G01X1113922Y219793D02*
X1121763Y223713D01*
X1121764Y223714D01*
G02X1124266Y218790I1267J-2454D01*
G01X1116392Y214853D01*
G02X1113922Y219793I-1235J2470D01*
G37*
G36*
G01Y235541D02*
X1121763Y239461D01*
X1121764Y239462D01*
G02X1124266Y234538I1267J-2454D01*
G01X1116392Y230601D01*
G02X1113922Y235541I-1235J2470D01*
G37*
G36*
G01Y251289D02*
X1121763Y255209D01*
X1121764Y255210D01*
G02X1124266Y250286I1267J-2454D01*
G01X1116392Y246349D01*
G02X1113922Y251289I-1235J2470D01*
G37*
G36*
G01X1104199Y254058D02*
X1104034Y254128D01*
X1104032Y254124D01*
X1096156Y258062D01*
Y258070D01*
X1096053Y258127D01*
G02X1098557Y263265I1388J2503D01*
G01X1098722Y263195D01*
X1098724Y263199D01*
X1106601Y259261D01*
X1106599Y259257D01*
X1106767Y259158D01*
G02X1104199Y254058I-1453J-2465D01*
G37*
G36*
G01Y238310D02*
X1104034Y238380D01*
X1104032Y238376D01*
X1096156Y242314D01*
Y242322D01*
X1096053Y242379D01*
G02X1098557Y247517I1388J2503D01*
G01X1098722Y247447D01*
X1098724Y247451D01*
X1106601Y243513D01*
X1106599Y243509D01*
X1106767Y243410D01*
G02X1104199Y238310I-1453J-2465D01*
G37*
G36*
G01X1113922Y172549D02*
X1121763Y176469D01*
X1121764Y176470D01*
G02X1124266Y171546I1267J-2454D01*
G01X1116392Y167609D01*
G02X1113922Y172549I-1235J2470D01*
G37*
G36*
G01Y188297D02*
X1121763Y192217D01*
X1121764Y192218D01*
G02X1124266Y187294I1267J-2454D01*
G01X1116392Y183357D01*
G02X1113922Y188297I-1235J2470D01*
G37*
G36*
G01X1104199Y175318D02*
X1104034Y175388D01*
X1104032Y175384D01*
X1096156Y179322D01*
Y179330D01*
X1096053Y179387D01*
G02X1098557Y184525I1388J2503D01*
G01X1098722Y184455D01*
X1098724Y184459D01*
X1106601Y180521D01*
X1106599Y180517D01*
X1106767Y180418D01*
G02X1104199Y175318I-1453J-2465D01*
G37*
G36*
G01Y206814D02*
X1104034Y206884D01*
X1104032Y206880D01*
X1096156Y210818D01*
Y210826D01*
X1096053Y210883D01*
G02X1098557Y216021I1388J2503D01*
G01X1098722Y215951D01*
X1098724Y215955D01*
X1106601Y212017D01*
X1106599Y212013D01*
X1106767Y211914D01*
G02X1104199Y206814I-1453J-2465D01*
G37*
G36*
G01X1113922Y204045D02*
X1121763Y207965D01*
X1121764Y207966D01*
G02X1124266Y203042I1267J-2454D01*
G01X1116392Y199105D01*
G02X1113922Y204045I-1235J2470D01*
G37*
G36*
G01X1104199Y191066D02*
X1104034Y191136D01*
X1104032Y191132D01*
X1096156Y195070D01*
Y195078D01*
X1096053Y195135D01*
G02X1098557Y200273I1388J2503D01*
G01X1098722Y200203D01*
X1098724Y200207D01*
X1106601Y196269D01*
X1106599Y196265D01*
X1106767Y196166D01*
G02X1104199Y191066I-1453J-2465D01*
G37*
G36*
G01X1124320Y139943D02*
X1116446Y136006D01*
G02X1113868Y141160I-1289J2577D01*
G01X1121741Y145097D01*
G02X1124320Y139943I1290J-2577D01*
G37*
G36*
G01X1113922Y156801D02*
X1121763Y160721D01*
X1121764Y160722D01*
G02X1124266Y155798I1267J-2454D01*
G01X1116392Y151861D01*
G02X1113922Y156801I-1235J2470D01*
G37*
G36*
G01X1104199Y143822D02*
X1104034Y143892D01*
X1104032Y143888D01*
X1096156Y147826D01*
Y147834D01*
X1096053Y147891D01*
G02X1098557Y153029I1388J2503D01*
G01X1098722Y152959D01*
X1098724Y152963D01*
X1106601Y149025D01*
X1106599Y149021D01*
X1106767Y148922D01*
G02X1104199Y143822I-1453J-2465D01*
G37*
G36*
G01Y159570D02*
X1104034Y159640D01*
X1104032Y159636D01*
X1096156Y163574D01*
Y163582D01*
X1096053Y163639D01*
G02X1098557Y168777I1388J2503D01*
G01X1098722Y168707D01*
X1098724Y168711D01*
X1106601Y164773D01*
X1106599Y164769D01*
X1106767Y164670D01*
G02X1104199Y159570I-1453J-2465D01*
G37*
G36*
G01X1098730Y50609D02*
X1106604Y46672D01*
G02X1104026Y41518I-1289J-2577D01*
G01X1096195Y45434D01*
X1096194D01*
G02X1098730Y50609I1248J2597D01*
G37*
G36*
G01X1104199Y65082D02*
X1104034Y65152D01*
X1104032Y65148D01*
X1096156Y69086D01*
Y69094D01*
X1096053Y69151D01*
G02X1098557Y74289I1388J2503D01*
G01X1098722Y74219D01*
X1098724Y74223D01*
X1106601Y70285D01*
X1106599Y70281D01*
X1106767Y70182D01*
G02X1104199Y65082I-1453J-2465D01*
G37*
G36*
G01X1075250Y1413872D02*
X1070749D01*
G02X1070750Y1416876I1J1502D01*
G01X1075250D01*
G02Y1413872I0J-1502D01*
G37*
G36*
G01Y1406786D02*
X1070749D01*
G02X1070750Y1409788I1J1501D01*
G01X1075250D01*
G02Y1406786I0J-1501D01*
G37*
G36*
G01Y1399700D02*
X1070749D01*
G02X1070750Y1402702I1J1501D01*
G01X1075250D01*
G02Y1399700I0J-1501D01*
G37*
G36*
G01Y1392612D02*
X1070749D01*
G02X1070750Y1395616I1J1502D01*
G01X1075250D01*
G02Y1392612I0J-1502D01*
G37*
G36*
G01Y1385526D02*
X1070749D01*
G02X1070750Y1388530I1J1502D01*
G01X1075250D01*
G02Y1385526I0J-1502D01*
G37*
G36*
G01Y1378440D02*
X1070749D01*
G02X1070750Y1381442I1J1501D01*
G01X1075250D01*
G02Y1378440I0J-1501D01*
G37*
G36*
G01Y1328824D02*
X1070749D01*
G02X1070750Y1331846I1J1511D01*
G01X1075250D01*
G02Y1328824I0J-1511D01*
G37*
G36*
G01Y1321736D02*
X1070749D01*
G02X1070750Y1324760I1J1512D01*
G01X1075250D01*
G02Y1321736I0J-1512D01*
G37*
G36*
G01Y1314650D02*
X1070749D01*
G02X1070750Y1317672I1J1511D01*
G01X1075250D01*
G02Y1314650I0J-1511D01*
G37*
G36*
G01Y1307564D02*
X1070749D01*
G02X1070750Y1310586I1J1511D01*
G01X1075250D01*
G02Y1307564I0J-1511D01*
G37*
G36*
G01Y1300476D02*
X1070749D01*
G02X1070750Y1303500I1J1512D01*
G01X1075250D01*
G02Y1300476I0J-1512D01*
G37*
G36*
G01Y1293390D02*
X1070749D01*
G02X1070750Y1296414I1J1512D01*
G01X1075250D01*
G02Y1293390I0J-1512D01*
G37*
G36*
G01Y1229610D02*
X1070749D01*
G02X1070750Y1232634I1J1512D01*
G01X1075250D01*
G02Y1229610I0J-1512D01*
G37*
G36*
G01Y1236698D02*
X1070749D01*
G02X1070750Y1239720I1J1511D01*
G01X1075250D01*
G02Y1236698I0J-1511D01*
G37*
G36*
G01Y1243784D02*
X1070749D01*
G02X1070750Y1246806I1J1511D01*
G01X1075250D01*
G02Y1243784I0J-1511D01*
G37*
G36*
G01Y1208350D02*
X1070749D01*
G02X1070750Y1211374I1J1512D01*
G01X1075250D01*
G02Y1208350I0J-1512D01*
G37*
G36*
G01Y1215438D02*
X1070749D01*
G02X1070750Y1218460I1J1511D01*
G01X1075250D01*
G02Y1215438I0J-1511D01*
G37*
G36*
G01Y1222524D02*
X1070749D01*
G02X1070750Y1225546I1J1511D01*
G01X1075250D01*
G02Y1222524I0J-1511D01*
G37*
G36*
G01X956156Y708159D02*
X948315Y704239D01*
X948314Y704238D01*
G02X945812Y709162I-1267J2454D01*
G01X953686Y713099D01*
G02X956156Y708159I1235J-2470D01*
G37*
G36*
G01Y660915D02*
X948315Y656995D01*
X948314Y656994D01*
G02X945812Y661918I-1267J2454D01*
G01X953686Y665855D01*
G02X956156Y660915I1235J-2470D01*
G37*
G36*
G01Y692411D02*
X948315Y688491D01*
X948314Y688490D01*
G02X945812Y693414I-1267J2454D01*
G01X953686Y697351D01*
G02X956156Y692411I1235J-2470D01*
G37*
G36*
G01Y676663D02*
X948315Y672743D01*
X948314Y672742D01*
G02X945812Y677666I-1267J2454D01*
G01X953686Y681603D01*
G02X956156Y676663I1235J-2470D01*
G37*
G36*
G01X956210Y645060D02*
X948337Y641123D01*
G02X945758Y646277I-1290J2577D01*
G01X953632Y650214D01*
G02X956210Y645060I1289J-2577D01*
G37*
G36*
G01X945758Y630529D02*
X953631Y634466D01*
G02X956210Y629312I1290J-2577D01*
G01X948336Y625375D01*
G02X945758Y630529I-1289J2577D01*
G37*
G36*
G01Y614781D02*
X953631Y618718D01*
G02X956210Y613564I1290J-2577D01*
G01X948336Y609627D01*
G02X945758Y614781I-1289J2577D01*
G37*
G36*
G01X956210Y597816D02*
X948337Y593879D01*
G02X945758Y599033I-1290J2577D01*
G01X953632Y602970D01*
G02X956210Y597816I1289J-2577D01*
G37*
G36*
G01X956223Y503301D02*
X948392Y499386D01*
G02X945745Y504572I-1345J2582D01*
G01X953619Y508509D01*
G02X956223Y503301I1302J-2604D01*
G37*
G36*
G01X945745Y488824D02*
X953576Y492739D01*
G02X956223Y487553I1345J-2582D01*
G01X948349Y483616D01*
G02X945745Y488824I-1302J2604D01*
G37*
G36*
G01X945758Y473049D02*
X953631Y476986D01*
G02X956210Y471832I1290J-2577D01*
G01X948336Y467895D01*
G02X945758Y473049I-1289J2577D01*
G37*
G36*
G01X956210Y456084D02*
X948337Y452147D01*
G02X945758Y457301I-1290J2577D01*
G01X953632Y461238D01*
G02X956210Y456084I1289J-2577D01*
G37*
G36*
G01X945812Y314281D02*
X953653Y318201D01*
X953654Y318202D01*
G02X956156Y313278I1267J-2454D01*
G01X948282Y309341D01*
G02X945812Y314281I-1235J2470D01*
G37*
G36*
G01X956156Y329026D02*
X948315Y325106D01*
X948314Y325105D01*
G02X945812Y330029I-1267J2454D01*
G01X953686Y333966D01*
G02X956156Y329026I1235J-2470D01*
G37*
G36*
G01Y266034D02*
X948315Y262114D01*
X948314Y262113D01*
G02X945812Y267037I-1267J2454D01*
G01X953686Y270974D01*
G02X956156Y266034I1235J-2470D01*
G37*
G36*
G01X945812Y282785D02*
X953653Y286705D01*
X953654Y286706D01*
G02X956156Y281782I1267J-2454D01*
G01X948282Y277845D01*
G02X945812Y282785I-1235J2470D01*
G37*
G36*
G01Y298533D02*
X953653Y302453D01*
X953654Y302454D01*
G02X956156Y297530I1267J-2454D01*
G01X948282Y293593D01*
G02X945812Y298533I-1235J2470D01*
G37*
G36*
G01X956156Y218790D02*
X948315Y214870D01*
X948314Y214869D01*
G02X945812Y219793I-1267J2454D01*
G01X953686Y223730D01*
G02X956156Y218790I1235J-2470D01*
G37*
G36*
G01Y234538D02*
X948315Y230618D01*
X948314Y230617D01*
G02X945812Y235541I-1267J2454D01*
G01X953686Y239478D01*
G02X956156Y234538I1235J-2470D01*
G37*
G36*
G01Y250286D02*
X948315Y246366D01*
X948314Y246365D01*
G02X945812Y251289I-1267J2454D01*
G01X953686Y255226D01*
G02X956156Y250286I1235J-2470D01*
G37*
G36*
G01Y171546D02*
X948315Y167626D01*
X948314Y167625D01*
G02X945812Y172549I-1267J2454D01*
G01X953686Y176486D01*
G02X956156Y171546I1235J-2470D01*
G37*
G36*
G01Y187294D02*
X948315Y183374D01*
X948314Y183373D01*
G02X945812Y188297I-1267J2454D01*
G01X953686Y192234D01*
G02X956156Y187294I1235J-2470D01*
G37*
G36*
G01X945812Y204045D02*
X953653Y207965D01*
X953654Y207966D01*
G02X956156Y203042I1267J-2454D01*
G01X948282Y199105D01*
G02X945812Y204045I-1235J2470D01*
G37*
G36*
G01X945762Y141151D02*
X953636Y145088D01*
G02X956206Y139952I1285J-2568D01*
G01X948332Y136015D01*
G02X945762Y141151I-1285J2568D01*
G37*
G36*
G01X956156Y155798D02*
X948315Y151878D01*
X948314Y151877D01*
G02X945812Y156801I-1267J2454D01*
G01X953686Y160738D01*
G02X956156Y155798I1235J-2470D01*
G37*
G36*
G01X936089Y696183D02*
X935924Y696253D01*
X935922Y696249D01*
X928046Y700187D01*
Y700195D01*
X927943Y700252D01*
G02X930447Y705390I1388J2503D01*
G01X930612Y705320D01*
X930614Y705324D01*
X938491Y701386D01*
X938489Y701382D01*
X938657Y701283D01*
G02X936089Y696183I-1453J-2465D01*
G37*
G36*
G01Y680435D02*
X935924Y680505D01*
X935922Y680501D01*
X928046Y684439D01*
Y684447D01*
X927943Y684504D01*
G02X930447Y689642I1388J2503D01*
G01X930612Y689572D01*
X930614Y689576D01*
X938491Y685638D01*
X938489Y685634D01*
X938657Y685535D01*
G02X936089Y680435I-1453J-2465D01*
G37*
G36*
G01Y664687D02*
X935924Y664757D01*
X935922Y664753D01*
X928046Y668691D01*
Y668699D01*
X927943Y668756D01*
G02X930447Y673894I1388J2503D01*
G01X930612Y673824D01*
X930614Y673828D01*
X938491Y669890D01*
X938489Y669886D01*
X938657Y669787D01*
G02X936089Y664687I-1453J-2465D01*
G37*
G36*
G01Y648939D02*
X935924Y649009D01*
X935922Y649005D01*
X928046Y652943D01*
Y652951D01*
X927943Y653008D01*
G02X930447Y658146I1388J2503D01*
G01X930612Y658076D01*
X930614Y658080D01*
X938491Y654142D01*
X938489Y654138D01*
X938657Y654039D01*
G02X936089Y648939I-1453J-2465D01*
G37*
G36*
G01X935916Y601753D02*
X928085Y605669D01*
X928084D01*
G02X930620Y610844I1248J2597D01*
G01X938494Y606907D01*
G02X935916Y601753I-1289J-2577D01*
G37*
G36*
G01Y633249D02*
X928085Y637165D01*
X928084D01*
G02X930620Y642340I1248J2597D01*
G01X938494Y638403D01*
G02X935916Y633249I-1289J-2577D01*
G37*
G36*
G01Y617501D02*
X928085Y621417D01*
X928084D01*
G02X930620Y626592I1248J2597D01*
G01X938494Y622655D01*
G02X935916Y617501I-1289J-2577D01*
G37*
G36*
G01Y586005D02*
X928085Y589921D01*
X928084D01*
G02X930620Y595096I1248J2597D01*
G01X938494Y591159D01*
G02X935916Y586005I-1289J-2577D01*
G37*
G36*
G01X936089Y538703D02*
X935924Y538773D01*
X935922Y538769D01*
X928046Y542707D01*
Y542715D01*
X927943Y542772D01*
G02X930447Y547910I1388J2503D01*
G01X930612Y547840D01*
X930614Y547844D01*
X938491Y543906D01*
X938489Y543902D01*
X938657Y543803D01*
G02X936089Y538703I-1453J-2465D01*
G37*
G36*
G01X935916Y507265D02*
X928085Y511181D01*
X928084D01*
G02X930620Y516356I1248J2597D01*
G01X938494Y512419D01*
G02X935916Y507265I-1289J-2577D01*
G37*
G36*
G01Y491517D02*
X928085Y495433D01*
X928084D01*
G02X930620Y500608I1248J2597D01*
G01X938494Y496671D01*
G02X935916Y491517I-1289J-2577D01*
G37*
G36*
G01X930620Y484860D02*
X938451Y480944D01*
X938452D01*
G02X935916Y475769I-1248J-2597D01*
G01X928042Y479706D01*
G02X930620Y484860I1289J2577D01*
G37*
G36*
G01X935916Y460021D02*
X928085Y463937D01*
X928084D01*
G02X930620Y469112I1248J2597D01*
G01X938494Y465175D01*
G02X935916Y460021I-1289J-2577D01*
G37*
G36*
G01Y444273D02*
X928085Y448189D01*
X928084D01*
G02X930620Y453364I1248J2597D01*
G01X938494Y449427D01*
G02X935916Y444273I-1289J-2577D01*
G37*
G36*
G01X936089Y317050D02*
X935924Y317120D01*
X935922Y317116D01*
X928046Y321054D01*
Y321062D01*
X927943Y321119D01*
G02X930447Y326257I1388J2503D01*
G01X930612Y326187D01*
X930614Y326191D01*
X938491Y322253D01*
X938489Y322249D01*
X938657Y322150D01*
G02X936089Y317050I-1453J-2465D01*
G37*
G36*
G01Y269806D02*
X935924Y269876D01*
X935922Y269872D01*
X928046Y273810D01*
Y273818D01*
X927943Y273875D01*
G02X930447Y279013I1388J2503D01*
G01X930612Y278943D01*
X930614Y278947D01*
X938491Y275009D01*
X938489Y275005D01*
X938657Y274906D01*
G02X936089Y269806I-1453J-2465D01*
G37*
G36*
G01Y301302D02*
X935924Y301372D01*
X935922Y301368D01*
X928046Y305306D01*
Y305314D01*
X927943Y305371D01*
G02X930447Y310509I1388J2503D01*
G01X930612Y310439D01*
X930614Y310443D01*
X938491Y306505D01*
X938489Y306501D01*
X938657Y306402D01*
G02X936089Y301302I-1453J-2465D01*
G37*
G36*
G01Y285554D02*
X935924Y285624D01*
X935922Y285620D01*
X928046Y289558D01*
Y289566D01*
X927943Y289623D01*
G02X930447Y294761I1388J2503D01*
G01X930612Y294691D01*
X930614Y294695D01*
X938491Y290757D01*
X938489Y290753D01*
X938657Y290654D01*
G02X936089Y285554I-1453J-2465D01*
G37*
G36*
G01Y222562D02*
X935924Y222632D01*
X935922Y222628D01*
X928046Y226566D01*
Y226574D01*
X927943Y226631D01*
G02X930447Y231769I1388J2503D01*
G01X930612Y231699D01*
X930614Y231703D01*
X938491Y227765D01*
X938489Y227761D01*
X938657Y227662D01*
G02X936089Y222562I-1453J-2465D01*
G37*
G36*
G01Y254058D02*
X935924Y254128D01*
X935922Y254124D01*
X928045Y258062D01*
X928047Y258066D01*
X927879Y258165D01*
G02X930447Y263265I1453J2465D01*
G01X930612Y263195D01*
X930614Y263199D01*
X938490Y259261D01*
Y259253D01*
X938593Y259196D01*
G02X936089Y254058I-1388J-2503D01*
G37*
G36*
G01Y238310D02*
X935924Y238380D01*
X935922Y238376D01*
X928046Y242314D01*
Y242322D01*
X927943Y242379D01*
G02X930447Y247517I1388J2503D01*
G01X930612Y247447D01*
X930614Y247451D01*
X938491Y243513D01*
X938489Y243509D01*
X938657Y243410D01*
G02X936089Y238310I-1453J-2465D01*
G37*
G36*
G01Y175318D02*
X935924Y175388D01*
X935922Y175384D01*
X928046Y179322D01*
Y179330D01*
X927943Y179387D01*
G02X930447Y184525I1388J2503D01*
G01X930612Y184455D01*
X930614Y184459D01*
X938491Y180521D01*
X938489Y180517D01*
X938657Y180418D01*
G02X936089Y175318I-1453J-2465D01*
G37*
G36*
G01Y191066D02*
X935924Y191136D01*
X935922Y191132D01*
X928046Y195070D01*
Y195078D01*
X927943Y195135D01*
G02X930447Y200273I1388J2503D01*
G01X930612Y200203D01*
X930614Y200207D01*
X938491Y196269D01*
X938489Y196265D01*
X938657Y196166D01*
G02X936089Y191066I-1453J-2465D01*
G37*
G36*
G01Y206814D02*
X935924Y206884D01*
X935922Y206880D01*
X928046Y210818D01*
Y210826D01*
X927943Y210883D01*
G02X930447Y216021I1388J2503D01*
G01X930612Y215951D01*
X930614Y215955D01*
X938491Y212017D01*
X938489Y212013D01*
X938657Y211914D01*
G02X936089Y206814I-1453J-2465D01*
G37*
G36*
G01Y159570D02*
X935924Y159640D01*
X935922Y159636D01*
X928046Y163574D01*
Y163582D01*
X927943Y163639D01*
G02X930447Y168777I1388J2503D01*
G01X930612Y168707D01*
X930614Y168711D01*
X938491Y164773D01*
X938489Y164769D01*
X938657Y164670D01*
G02X936089Y159570I-1453J-2465D01*
G37*
G36*
G01Y143822D02*
X935924Y143892D01*
X935922Y143888D01*
X928046Y147826D01*
Y147834D01*
X927943Y147891D01*
G02X930447Y153029I1388J2503D01*
G01X930612Y152959D01*
X930614Y152963D01*
X938491Y149025D01*
X938489Y149021D01*
X938657Y148922D01*
G02X936089Y143822I-1453J-2465D01*
G37*
G36*
G01X930620Y50609D02*
X938494Y46672D01*
G02X935916Y41518I-1289J-2577D01*
G01X928085Y45434D01*
X928084D01*
G02X930620Y50609I1248J2597D01*
G37*
G36*
G01X936089Y65082D02*
X935924Y65152D01*
X935922Y65148D01*
X928046Y69086D01*
Y69094D01*
X927943Y69151D01*
G02X930447Y74289I1388J2503D01*
G01X930612Y74219D01*
X930614Y74223D01*
X938491Y70285D01*
X938489Y70281D01*
X938657Y70182D01*
G02X936089Y65082I-1453J-2465D01*
G37*
G36*
G01X878540Y1646457D02*
Y1640944D01*
G02X874216Y1640945I-2162J1D01*
G01Y1646457D01*
G02X878540I2162J0D01*
G37*
G36*
G01X871454Y1636221D02*
Y1630708D01*
G02X867130Y1630709I-2162J1D01*
G01Y1636221D01*
G02X871454I2162J0D01*
G37*
G36*
G01X864366Y1646457D02*
Y1640944D01*
G02X860044Y1640945I-2161J1D01*
G01Y1646457D01*
G02X864366I2161J0D01*
G37*
G36*
G01X857280Y1636221D02*
Y1630708D01*
G02X852956Y1630709I-2162J1D01*
G01Y1636221D01*
G02X857280I2162J0D01*
G37*
G36*
G01X850194Y1646457D02*
Y1640944D01*
G02X845870Y1640945I-2162J1D01*
G01Y1646457D01*
G02X850194I2162J0D01*
G37*
G36*
G01X878540Y1603937D02*
Y1598424D01*
G02X874216Y1598425I-2162J1D01*
G01Y1603937D01*
G02X878540I2162J0D01*
G37*
G36*
G01X871454Y1607874D02*
Y1602362D01*
G02X867130Y1602363I-2162J1D01*
G01Y1607874D01*
G02X871454I2162J0D01*
G37*
G36*
G01X864366Y1603937D02*
Y1598424D01*
G02X860044Y1598425I-2161J1D01*
G01Y1603937D01*
G02X864366I2161J0D01*
G37*
G36*
G01X857280Y1607874D02*
Y1602362D01*
G02X852956Y1602363I-2162J1D01*
G01Y1607874D01*
G02X857280I2162J0D01*
G37*
G36*
G01X850194Y1603937D02*
Y1598424D01*
G02X845870Y1598425I-2162J1D01*
G01Y1603937D01*
G02X850194I2162J0D01*
G37*
G36*
G01X843106Y1636221D02*
Y1630708D01*
G02X838784Y1630709I-2161J1D01*
G01Y1636221D01*
G02X843106I2161J0D01*
G37*
G36*
G01X836020Y1646457D02*
Y1640944D01*
G02X831698Y1640945I-2161J1D01*
G01Y1646457D01*
G02X836020I2161J0D01*
G37*
G36*
G01X828934Y1636221D02*
Y1630708D01*
G02X824610Y1630709I-2162J1D01*
G01Y1636221D01*
G02X828934I2162J0D01*
G37*
G36*
G01Y1622048D02*
Y1616535D01*
G02X824610Y1616536I-2162J1D01*
G01Y1622048D01*
G02X828934I2162J0D01*
G37*
G36*
G01X843106Y1607874D02*
Y1602362D01*
G02X838784Y1602363I-2161J1D01*
G01Y1607874D01*
G02X843106I2161J0D01*
G37*
G36*
G01X836020Y1603937D02*
Y1598424D01*
G02X831698Y1598425I-2161J1D01*
G01Y1603937D01*
G02X836020I2161J0D01*
G37*
G36*
G01X828934Y1607874D02*
Y1602362D01*
G02X824610Y1602363I-2162J1D01*
G01Y1607874D01*
G02X828934I2162J0D01*
G37*
G36*
G01X747070Y1077004D02*
Y1077804D01*
G02X747272Y1078006I202J0D01*
G01X750472D01*
G02X750674Y1077804I0J-202D01*
G01Y1077004D01*
G02X750472Y1076802I-202J0D01*
G01X747272D01*
G02X747070Y1077004I0J202D01*
G37*
G36*
G01Y1079204D02*
Y1080004D01*
G02X747272Y1080206I202J0D01*
G01X750472D01*
G02X750674Y1080004I0J-202D01*
G01Y1079204D01*
G02X750472Y1079002I-202J0D01*
G01X747272D01*
G02X747070Y1079204I0J202D01*
G37*
G36*
G01Y624248D02*
Y625048D01*
G02X747272Y625250I202J0D01*
G01X750472D01*
G02X750674Y625048I0J-202D01*
G01Y624248D01*
G02X750472Y624046I-202J0D01*
G01X747272D01*
G02X747070Y624248I0J202D01*
G37*
G36*
G01Y626448D02*
Y627248D01*
G02X747272Y627450I202J0D01*
G01X750472D01*
G02X750674Y627248I0J-202D01*
G01Y626448D01*
G02X750472Y626246I-202J0D01*
G01X747272D01*
G02X747070Y626448I0J202D01*
G37*
G36*
G01Y173692D02*
Y174492D01*
G02X747272Y174694I202J0D01*
G01X750472D01*
G02X750674Y174492I0J-202D01*
G01Y173692D01*
G02X750472Y173490I-202J0D01*
G01X747272D01*
G02X747070Y173692I0J202D01*
G37*
G36*
G01Y171492D02*
Y172292D01*
G02X747272Y172494I202J0D01*
G01X750472D01*
G02X750674Y172292I0J-202D01*
G01Y171492D01*
G02X750472Y171290I-202J0D01*
G01X747272D01*
G02X747070Y171492I0J202D01*
G37*
G36*
G01X622858Y1077004D02*
Y1077804D01*
G02X623059Y1078006I201J1D01*
G01X626259D01*
G02X626460Y1077804I-1J-202D01*
G01Y1077004D01*
G02X626259Y1076802I-201J-1D01*
G01X623059D01*
G02X622858Y1077004I1J202D01*
G37*
G36*
G01Y1079204D02*
Y1080004D01*
G02X623059Y1080206I201J1D01*
G01X626259D01*
G02X626460Y1080004I-1J-202D01*
G01Y1079204D01*
G02X626259Y1079002I-201J-1D01*
G01X623059D01*
G02X622858Y1079204I1J202D01*
G37*
G36*
G01Y624248D02*
Y625048D01*
G02X623059Y625250I201J1D01*
G01X626259D01*
G02X626460Y625048I-1J-202D01*
G01Y624248D01*
G02X626259Y624046I-201J-1D01*
G01X623059D01*
G02X622858Y624248I1J202D01*
G37*
G36*
G01Y626448D02*
Y627248D01*
G02X623059Y627450I201J1D01*
G01X626259D01*
G02X626460Y627248I-1J-202D01*
G01Y626448D01*
G02X626259Y626246I-201J-1D01*
G01X623059D01*
G02X622858Y626448I1J202D01*
G37*
G36*
G01Y173692D02*
Y174492D01*
G02X623059Y174694I201J1D01*
G01X626259D01*
G02X626460Y174492I-1J-202D01*
G01Y173692D01*
G02X626259Y173490I-201J-1D01*
G01X623059D01*
G02X622858Y173692I1J202D01*
G37*
G36*
G01Y171492D02*
Y172292D01*
G02X623059Y172494I201J1D01*
G01X626259D01*
G02X626460Y172292I-1J-202D01*
G01Y171492D01*
G02X626259Y171290I-201J-1D01*
G01X623059D01*
G02X622858Y171492I1J202D01*
G37*
G36*
G01X566532Y91930D02*
Y86417D01*
G02X562208Y86418I-2162J1D01*
G01Y91930D01*
G02X566532I2162J0D01*
G37*
G36*
G01Y77756D02*
Y72244D01*
G02X562208Y72245I-2162J1D01*
G01Y77756D01*
G02X566532I2162J0D01*
G37*
G36*
G01Y120276D02*
Y114763D01*
G02X562208Y114764I-2162J1D01*
G01Y120276D01*
G02X566532I2162J0D01*
G37*
G36*
G01X519688Y72245D02*
Y77757D01*
G02X524012Y77756I2162J-1D01*
G01Y72245D01*
G02X519688I-2162J0D01*
G37*
G36*
G01X516926Y87993D02*
Y82480D01*
G02X512602Y82481I-2162J1D01*
G01Y87993D01*
G02X516926I2162J0D01*
G37*
G36*
G01X524012Y91930D02*
Y86417D01*
G02X519688Y86418I-2162J1D01*
G01Y91930D01*
G02X524012I2162J0D01*
G37*
G36*
G01X531098Y87993D02*
Y82480D01*
G02X526776Y82481I-2161J1D01*
G01Y87993D01*
G02X531098I2161J0D01*
G37*
G36*
G01X538186Y91930D02*
Y86417D01*
G02X533862Y86418I-2162J1D01*
G01Y91930D01*
G02X538186I2162J0D01*
G37*
G36*
G01Y77756D02*
Y72244D01*
G02X533862Y72245I-2162J1D01*
G01Y77756D01*
G02X538186I2162J0D01*
G37*
G36*
G01Y120276D02*
Y114763D01*
G02X533862Y114764I-2162J1D01*
G01Y120276D01*
G02X538186I2162J0D01*
G37*
G36*
G01X545272Y87993D02*
Y82480D01*
G02X540948Y82481I-2162J1D01*
G01Y87993D01*
G02X545272I2162J0D01*
G37*
G36*
G01X552358Y91930D02*
Y86417D01*
G02X548036Y86418I-2161J1D01*
G01Y91930D01*
G02X552358I2161J0D01*
G37*
G36*
G01X559444Y87993D02*
Y82480D01*
G02X555122Y82481I-2161J1D01*
G01Y87993D01*
G02X559444I2161J0D01*
G37*
G36*
G01X552358Y77756D02*
Y72244D01*
G02X548036Y72245I-2161J1D01*
G01Y77756D01*
G02X552358I2161J0D01*
G37*
G36*
G01X516926Y73819D02*
Y68306D01*
G02X512602Y68307I-2162J1D01*
G01Y73819D01*
G02X516926I2162J0D01*
G37*
G36*
G01X531098D02*
Y68306D01*
G02X526776Y68307I-2161J1D01*
G01Y73819D01*
G02X531098I2161J0D01*
G37*
G36*
G01X545272D02*
Y68306D01*
G02X540948Y68307I-2162J1D01*
G01Y73819D01*
G02X545272I2162J0D01*
G37*
G36*
G01X559444D02*
Y68306D01*
G02X555122Y68307I-2161J1D01*
G01Y73819D01*
G02X559444I2161J0D01*
G37*
G36*
G01X498644Y1077004D02*
Y1077804D01*
G02X498846Y1078006I202J0D01*
G01X502046D01*
G02X502248Y1077804I0J-202D01*
G01Y1077004D01*
G02X502046Y1076802I-202J0D01*
G01X498846D01*
G02X498644Y1077004I0J202D01*
G37*
G36*
G01Y1079204D02*
Y1080004D01*
G02X498846Y1080206I202J0D01*
G01X502046D01*
G02X502248Y1080004I0J-202D01*
G01Y1079204D01*
G02X502046Y1079002I-202J0D01*
G01X498846D01*
G02X498644Y1079204I0J202D01*
G37*
G36*
G01Y624248D02*
Y625048D01*
G02X498846Y625250I202J0D01*
G01X502046D01*
G02X502248Y625048I0J-202D01*
G01Y624248D01*
G02X502046Y624046I-202J0D01*
G01X498846D01*
G02X498644Y624248I0J202D01*
G37*
G36*
G01Y626448D02*
Y627248D01*
G02X498846Y627450I202J0D01*
G01X502046D01*
G02X502248Y627248I0J-202D01*
G01Y626448D01*
G02X502046Y626246I-202J0D01*
G01X498846D01*
G02X498644Y626448I0J202D01*
G37*
G36*
G01Y173692D02*
Y174492D01*
G02X498846Y174694I202J0D01*
G01X502046D01*
G02X502248Y174492I0J-202D01*
G01Y173692D01*
G02X502046Y173490I-202J0D01*
G01X498846D01*
G02X498644Y173692I0J202D01*
G37*
G36*
G01Y171492D02*
Y172292D01*
G02X498846Y172494I202J0D01*
G01X502046D01*
G02X502248Y172292I0J-202D01*
G01Y171492D01*
G02X502046Y171290I-202J0D01*
G01X498846D01*
G02X498644Y171492I0J202D01*
G37*
G36*
G01X481492Y91930D02*
Y86417D01*
G02X477170Y86418I-2161J1D01*
G01Y91930D01*
G02X481492I2161J0D01*
G37*
G36*
G01Y77756D02*
Y72244D01*
G02X477170Y72245I-2161J1D01*
G01Y77756D01*
G02X481492I2161J0D01*
G37*
G36*
G01X467318Y91930D02*
Y86417D01*
G02X462996Y86418I-2161J1D01*
G01Y91930D01*
G02X467318I2161J0D01*
G37*
G36*
G01X474406Y87993D02*
Y82480D01*
G02X470082Y82481I-2162J1D01*
G01Y87993D01*
G02X474406I2162J0D01*
G37*
G36*
G01X467318Y77756D02*
Y72244D01*
G02X462996Y72245I-2161J1D01*
G01Y77756D01*
G02X467318I2161J0D01*
G37*
G36*
G01X477160Y114764D02*
Y120277D01*
G02X481502Y120276I2171J-1D01*
G01Y114764D01*
G02X477160I-2171J0D01*
G37*
G36*
G01X474406Y73819D02*
Y68306D01*
G02X470082Y68307I-2162J1D01*
G01Y73819D01*
G02X474406I2162J0D01*
G37*
G36*
G01X438972Y77756D02*
Y72244D01*
G02X434650Y72245I-2161J1D01*
G01Y77756D01*
G02X438972I2161J0D01*
G37*
G36*
G01X431886Y87993D02*
Y82480D01*
G02X427562Y82481I-2162J1D01*
G01Y87993D01*
G02X431886I2162J0D01*
G37*
G36*
G01X438972Y91930D02*
Y86417D01*
G02X434650Y86418I-2161J1D01*
G01Y91930D01*
G02X438972I2161J0D01*
G37*
G36*
G01X446060Y87993D02*
Y82480D01*
G02X441736Y82481I-2162J1D01*
G01Y87993D01*
G02X446060I2162J0D01*
G37*
G36*
G01X453146Y91930D02*
Y86417D01*
G02X448822Y86418I-2162J1D01*
G01Y91930D01*
G02X453146I2162J0D01*
G37*
G36*
G01X460232Y87993D02*
Y82480D01*
G02X455910Y82481I-2161J1D01*
G01Y87993D01*
G02X460232I2161J0D01*
G37*
G36*
G01X453146Y77756D02*
Y72244D01*
G02X448822Y72245I-2162J1D01*
G01Y77756D01*
G02X453146I2162J0D01*
G37*
G36*
G01X455910Y110827D02*
Y116339D01*
G02X460232I2161J0D01*
G01Y110826D01*
G02X455910Y110827I-2161J1D01*
G37*
G36*
G01X431886Y73819D02*
Y68306D01*
G02X427562Y68307I-2162J1D01*
G01Y73819D01*
G02X431886I2162J0D01*
G37*
G36*
G01X446060D02*
Y68306D01*
G02X441736Y68307I-2162J1D01*
G01Y73819D01*
G02X446060I2162J0D01*
G37*
G36*
G01X460232D02*
Y68306D01*
G02X455910Y68307I-2161J1D01*
G01Y73819D01*
G02X460232I2161J0D01*
G37*
G36*
G01X374432Y1077004D02*
Y1077804D01*
G02X374634Y1078006I202J0D01*
G01X377834D01*
G02X378036Y1077804I0J-202D01*
G01Y1077004D01*
G02X377834Y1076802I-202J0D01*
G01X374634D01*
G02X374432Y1077004I0J202D01*
G37*
G36*
G01Y1079204D02*
Y1080004D01*
G02X374634Y1080206I202J0D01*
G01X377834D01*
G02X378036Y1080004I0J-202D01*
G01Y1079204D01*
G02X377834Y1079002I-202J0D01*
G01X374634D01*
G02X374432Y1079204I0J202D01*
G37*
G36*
G01Y624248D02*
Y625048D01*
G02X374634Y625250I202J0D01*
G01X377834D01*
G02X378036Y625048I0J-202D01*
G01Y624248D01*
G02X377834Y624046I-202J0D01*
G01X374634D01*
G02X374432Y624248I0J202D01*
G37*
G36*
G01Y626448D02*
Y627248D01*
G02X374634Y627450I202J0D01*
G01X377834D01*
G02X378036Y627248I0J-202D01*
G01Y626448D01*
G02X377834Y626246I-202J0D01*
G01X374634D01*
G02X374432Y626448I0J202D01*
G37*
G36*
G01Y171492D02*
Y172292D01*
G02X374634Y172494I202J0D01*
G01X377834D01*
G02X378036Y172292I0J-202D01*
G01Y171492D01*
G02X377834Y171290I-202J0D01*
G01X374634D01*
G02X374432Y171492I0J202D01*
G37*
G36*
G01Y173692D02*
Y174492D01*
G02X374634Y174694I202J0D01*
G01X377834D01*
G02X378036Y174492I0J-202D01*
G01Y173692D01*
G02X377834Y173490I-202J0D01*
G01X374634D01*
G02X374432Y173692I0J202D01*
G37*
G36*
G01X250220Y1079204D02*
Y1080004D01*
G02X250421Y1080206I201J1D01*
G01X253621D01*
G02X253822Y1080004I-1J-202D01*
G01Y1079204D01*
G02X253621Y1079002I-201J-1D01*
G01X250421D01*
G02X250220Y1079204I1J202D01*
G37*
G36*
G01Y1077004D02*
Y1077804D01*
G02X250421Y1078006I201J1D01*
G01X253621D01*
G02X253822Y1077804I-1J-202D01*
G01Y1077004D01*
G02X253621Y1076802I-201J-1D01*
G01X250421D01*
G02X250220Y1077004I1J202D01*
G37*
G36*
G01Y624248D02*
Y625048D01*
G02X250421Y625250I201J1D01*
G01X253621D01*
G02X253822Y625048I-1J-202D01*
G01Y624248D01*
G02X253621Y624046I-201J-1D01*
G01X250421D01*
G02X250220Y624248I1J202D01*
G37*
G36*
G01Y626448D02*
Y627248D01*
G02X250421Y627450I201J1D01*
G01X253621D01*
G02X253822Y627248I-1J-202D01*
G01Y626448D01*
G02X253621Y626246I-201J-1D01*
G01X250421D01*
G02X250220Y626448I1J202D01*
G37*
G36*
G01Y171492D02*
Y172292D01*
G02X250421Y172494I201J1D01*
G01X253621D01*
G02X253822Y172292I-1J-202D01*
G01Y171492D01*
G02X253621Y171290I-201J-1D01*
G01X250421D01*
G02X250220Y171492I1J202D01*
G37*
G36*
G01Y173692D02*
Y174492D01*
G02X250421Y174694I201J1D01*
G01X253621D01*
G02X253822Y174492I-1J-202D01*
G01Y173692D01*
G02X253621Y173490I-201J-1D01*
G01X250421D01*
G02X250220Y173692I1J202D01*
G37*
G36*
G01X126008Y1077004D02*
Y1077804D01*
G02X126209Y1078006I201J1D01*
G01X129409D01*
G02X129610Y1077804I-1J-202D01*
G01Y1077004D01*
G02X129409Y1076802I-201J-1D01*
G01X126209D01*
G02X126008Y1077004I1J202D01*
G37*
G36*
G01Y1079204D02*
Y1080004D01*
G02X126209Y1080206I201J1D01*
G01X129409D01*
G02X129610Y1080004I-1J-202D01*
G01Y1079204D01*
G02X129409Y1079002I-201J-1D01*
G01X126209D01*
G02X126008Y1079204I1J202D01*
G37*
G36*
G01Y624248D02*
Y625048D01*
G02X126209Y625250I201J1D01*
G01X129409D01*
G02X129610Y625048I-1J-202D01*
G01Y624248D01*
G02X129409Y624046I-201J-1D01*
G01X126209D01*
G02X126008Y624248I1J202D01*
G37*
G36*
G01Y626448D02*
Y627248D01*
G02X126209Y627450I201J1D01*
G01X129409D01*
G02X129610Y627248I-1J-202D01*
G01Y626448D01*
G02X129409Y626246I-201J-1D01*
G01X126209D01*
G02X126008Y626448I1J202D01*
G37*
G36*
G01Y171492D02*
Y172292D01*
G02X126209Y172494I201J1D01*
G01X129409D01*
G02X129610Y172292I-1J-202D01*
G01Y171492D01*
G02X129409Y171290I-201J-1D01*
G01X126209D01*
G02X126008Y171492I1J202D01*
G37*
G36*
G01Y173692D02*
Y174492D01*
G02X126209Y174694I201J1D01*
G01X129409D01*
G02X129610Y174492I-1J-202D01*
G01Y173692D01*
G02X129409Y173490I-201J-1D01*
G01X126209D01*
G02X126008Y173692I1J202D01*
G37*
G36*
G01X950928Y1489335D02*
X950891Y1489350D01*
X921734D01*
X908025Y1503059D01*
Y1513614D01*
X907689Y1513950D01*
X891789D01*
X888289Y1517450D01*
X877889D01*
X876250Y1519089D01*
Y1535511D01*
X887889Y1547150D01*
X897914D01*
X920710Y1569946D01*
X975435D01*
X983550Y1561831D01*
Y1531411D01*
X992450Y1522511D01*
Y1502289D01*
X979511Y1489350D01*
X952739D01*
X952702Y1489335D01*
G02X950928I-887J2124D01*
G37*
G36*
G01X1898061Y1091290D02*
X1898062Y1091293D01*
Y1095715D01*
X1898061Y1095718D01*
G02X1901065I1502J36D01*
G01X1901064Y1095715D01*
Y1091293D01*
X1901065Y1091290D01*
G02X1898061I-1502J-36D01*
G37*
G36*
G01X1776852Y1095718D02*
Y1091290D01*
G02X1773848I-1502J-36D01*
G01Y1095718D01*
G02X1776852I1502J36D01*
G37*
G36*
G01X1652640D02*
Y1091290D01*
G02X1649636I-1502J-36D01*
G01Y1095718D01*
G02X1652640I1502J36D01*
G37*
G36*
G01X1525423Y1091290D02*
X1525424Y1091293D01*
Y1095715D01*
X1525423Y1095718D01*
G02X1528427I1502J36D01*
G01X1528426Y1095715D01*
Y1091293D01*
X1528427Y1091290D01*
G02X1525423I-1502J-36D01*
G37*
G36*
G01X1401211D02*
X1401212Y1091293D01*
Y1095715D01*
X1401211Y1095718D01*
G02X1404215I1502J36D01*
G01X1404214Y1095715D01*
Y1091293D01*
X1404215Y1091290D01*
G02X1401211I-1502J-36D01*
G37*
G36*
G01X1280002Y1095718D02*
Y1091290D01*
G02X1276998I-1502J-36D01*
G01Y1095718D01*
G02X1280002I1502J36D01*
G37*
G36*
G01X747549Y1091290D02*
X747550Y1091293D01*
Y1095715D01*
X747549Y1095718D01*
G02X750553I1502J36D01*
G01X750552Y1095715D01*
Y1091293D01*
X750553Y1091290D01*
G02X747549I-1502J-36D01*
G37*
G36*
G01X626340Y1095718D02*
Y1091290D01*
G02X623336I-1502J-36D01*
G01Y1095718D01*
G02X626340I1502J36D01*
G37*
G36*
G01X499123Y1091290D02*
X499124Y1091293D01*
Y1095715D01*
X499123Y1095718D01*
G02X502127I1502J36D01*
G01X502126Y1095715D01*
Y1091293D01*
X502127Y1091290D01*
G02X499123I-1502J-36D01*
G37*
G36*
G01X374911D02*
X374912Y1091293D01*
Y1095715D01*
X374911Y1095718D01*
G02X377915I1502J36D01*
G01X377914Y1095715D01*
Y1091293D01*
X377915Y1091290D01*
G02X374911I-1502J-36D01*
G37*
G36*
G01X253702Y1095718D02*
Y1091290D01*
G02X250698I-1502J-36D01*
G01Y1095718D01*
G02X253702I1502J36D01*
G37*
G36*
G01X129490D02*
Y1091290D01*
G02X126486I-1502J-36D01*
G01Y1095718D01*
G02X129490I1502J36D01*
G37*
G36*
G01X1879361Y1076290D02*
X1879362Y1076293D01*
Y1080715D01*
X1879361Y1080718D01*
G02X1882365I1502J36D01*
G01X1882364Y1080715D01*
Y1076293D01*
X1882365Y1076290D01*
G02X1879361I-1502J-36D01*
G37*
G36*
G01X1758152Y1080718D02*
Y1076290D01*
G02X1755148I-1502J-36D01*
G01Y1080718D01*
G02X1758152I1502J36D01*
G37*
G36*
G01X1633940D02*
Y1076290D01*
G02X1630936I-1502J-36D01*
G01Y1080718D01*
G02X1633940I1502J36D01*
G37*
G36*
G01X1506723Y1076290D02*
X1506724Y1076293D01*
Y1080715D01*
X1506723Y1080718D01*
G02X1509727I1502J36D01*
G01X1509726Y1080715D01*
Y1076293D01*
X1509727Y1076290D01*
G02X1506723I-1502J-36D01*
G37*
G36*
G01X1382511D02*
X1382512Y1076293D01*
Y1080715D01*
X1382511Y1080718D01*
G02X1385515I1502J36D01*
G01X1385514Y1080715D01*
Y1076293D01*
X1385515Y1076290D01*
G02X1382511I-1502J-36D01*
G37*
G36*
G01X1905290Y1072202D02*
Y1084806D01*
X1914592D01*
Y1072206D01*
X1905290Y1072202D01*
G37*
G36*
G01X1781076D02*
Y1084806D01*
X1790380D01*
Y1072206D01*
X1781076Y1072202D01*
G37*
G36*
G01X1656864D02*
Y1084806D01*
X1666168D01*
Y1072206D01*
X1656864Y1072202D01*
G37*
G36*
G01X1532652D02*
Y1084806D01*
X1541954D01*
Y1072206D01*
X1532652Y1072202D01*
G37*
G36*
G01X1408440D02*
Y1084806D01*
X1417742D01*
Y1072206D01*
X1408440Y1072202D01*
G37*
G36*
G01X1284226D02*
Y1084806D01*
X1293530D01*
Y1072206D01*
X1284226Y1072202D01*
G37*
G36*
G01X734620D02*
Y1084806D01*
X743924D01*
Y1072206D01*
X734620Y1072202D01*
G37*
G36*
G01X610408D02*
Y1084806D01*
X619710D01*
Y1072206D01*
X610408Y1072202D01*
G37*
G36*
G01X486194D02*
Y1084806D01*
X495498D01*
Y1072206D01*
X486194Y1072202D01*
G37*
G36*
G01X361982D02*
Y1084806D01*
X371286D01*
Y1072206D01*
X361982Y1072202D01*
G37*
G36*
G01X237770D02*
Y1084806D01*
X247072D01*
Y1072206D01*
X237770Y1072202D01*
G37*
G36*
G01X113558D02*
Y1084806D01*
X122860D01*
Y1072206D01*
X113558Y1072202D01*
G37*
G36*
G01X1898061Y638534D02*
X1898062Y638537D01*
Y642959D01*
X1898061Y642962D01*
G02X1901065I1502J36D01*
G01X1901064Y642959D01*
Y638537D01*
X1901065Y638534D01*
G02X1898061I-1502J-36D01*
G37*
G36*
G01X1726852Y642962D02*
Y638534D01*
G02X1723848I-1502J-36D01*
G01Y642962D01*
G02X1726852I1502J36D01*
G37*
G36*
G01X1652640D02*
Y638534D01*
G02X1649636I-1502J-36D01*
G01Y642962D01*
G02X1652640I1502J36D01*
G37*
G36*
G01X1525423Y638534D02*
X1525424Y638537D01*
Y642959D01*
X1525423Y642962D01*
G02X1528427I1502J36D01*
G01X1528426Y642959D01*
Y638537D01*
X1528427Y638534D01*
G02X1525423I-1502J-36D01*
G37*
G36*
G01X1401211D02*
X1401212Y638537D01*
Y642959D01*
X1401211Y642962D01*
G02X1404215I1502J36D01*
G01X1404214Y642959D01*
Y638537D01*
X1404215Y638534D01*
G02X1401211I-1502J-36D01*
G37*
G36*
G01X1280002Y642962D02*
Y638534D01*
G02X1276998I-1502J-36D01*
G01Y642962D01*
G02X1280002I1502J36D01*
G37*
G36*
G01X747549Y638534D02*
X747550Y638537D01*
Y642959D01*
X747549Y642962D01*
G02X750553I1502J36D01*
G01X750552Y642959D01*
Y638537D01*
X750553Y638534D01*
G02X747549I-1502J-36D01*
G37*
G36*
G01X626340Y642962D02*
Y638534D01*
G02X623336I-1502J-36D01*
G01Y642962D01*
G02X626340I1502J36D01*
G37*
G36*
G01X499123Y638534D02*
X499124Y638537D01*
Y642959D01*
X499123Y642962D01*
G02X502127I1502J36D01*
G01X502126Y642959D01*
Y638537D01*
X502127Y638534D01*
G02X499123I-1502J-36D01*
G37*
G36*
G01X374911D02*
X374912Y638537D01*
Y642959D01*
X374911Y642962D01*
G02X377915I1502J36D01*
G01X377914Y642959D01*
Y638537D01*
X377915Y638534D01*
G02X374911I-1502J-36D01*
G37*
G36*
G01X253702Y642962D02*
Y638534D01*
G02X250698I-1502J-36D01*
G01Y642962D01*
G02X253702I1502J36D01*
G37*
G36*
G01X129490D02*
Y638534D01*
G02X126486I-1502J-36D01*
G01Y642962D01*
G02X129490I1502J36D01*
G37*
G36*
G01X1879361Y623534D02*
X1879362Y623537D01*
Y627959D01*
X1879361Y627962D01*
G02X1882365I1502J36D01*
G01X1882364Y627959D01*
Y623537D01*
X1882365Y623534D01*
G02X1879361I-1502J-36D01*
G37*
G36*
G01X1733152Y627962D02*
Y623534D01*
G02X1730148I-1502J-36D01*
G01Y627962D01*
G02X1733152I1502J36D01*
G37*
G36*
G01X1633940D02*
Y623534D01*
G02X1630936I-1502J-36D01*
G01Y627962D01*
G02X1633940I1502J36D01*
G37*
G36*
G01X1506723Y623534D02*
X1506724Y623537D01*
Y627959D01*
X1506723Y627962D01*
G02X1509727I1502J36D01*
G01X1509726Y627959D01*
Y623537D01*
X1509727Y623534D01*
G02X1506723I-1502J-36D01*
G37*
G36*
G01X1382511D02*
X1382512Y623537D01*
Y627959D01*
X1382511Y627962D01*
G02X1385515I1502J36D01*
G01X1385514Y627959D01*
Y623537D01*
X1385515Y623534D01*
G02X1382511I-1502J-36D01*
G37*
G36*
G01X1261302Y627962D02*
Y623534D01*
G02X1258298I-1502J-36D01*
G01Y627962D01*
G02X1261302I1502J36D01*
G37*
G36*
G01X1905290Y619446D02*
Y632050D01*
X1914592D01*
Y619450D01*
X1905290Y619446D01*
G37*
G36*
G01X1781076D02*
Y632050D01*
X1790380D01*
Y619450D01*
X1781076Y619446D01*
G37*
G36*
G01X1656864D02*
Y632050D01*
X1666168D01*
Y619450D01*
X1656864Y619446D01*
G37*
G36*
G01X1532652D02*
Y632050D01*
X1541954D01*
Y619450D01*
X1532652Y619446D01*
G37*
G36*
G01X1408440D02*
Y632050D01*
X1417742D01*
Y619450D01*
X1408440Y619446D01*
G37*
G36*
G01X1284226D02*
Y632050D01*
X1293530D01*
Y619450D01*
X1284226Y619446D01*
G37*
G36*
G01X734620D02*
Y632050D01*
X743924D01*
Y619450D01*
X734620Y619446D01*
G37*
G36*
G01X610408D02*
Y632050D01*
X619710D01*
Y619450D01*
X610408Y619446D01*
G37*
G36*
G01X486194D02*
Y632050D01*
X495498D01*
Y619450D01*
X486194Y619446D01*
G37*
G36*
G01X361982D02*
Y632050D01*
X371286D01*
Y619450D01*
X361982Y619446D01*
G37*
G36*
G01X237770D02*
Y632050D01*
X247072D01*
Y619450D01*
X237770Y619446D01*
G37*
G36*
G01X113558D02*
Y632050D01*
X122860D01*
Y619450D01*
X113558Y619446D01*
G37*
G36*
G01X542251Y583482D02*
X542285Y583324D01*
X613031D01*
X630250Y566105D01*
Y530489D01*
X618450Y518689D01*
Y512289D01*
X603011Y496850D01*
X557128D01*
X542450Y511528D01*
Y534889D01*
X541989Y535350D01*
X524389D01*
X507650Y552089D01*
Y581211D01*
X509763Y583324D01*
X537715D01*
X537749Y583482D01*
G02X542251I2251J-482D01*
G37*
G36*
G01X1898061Y185778D02*
X1898062Y185781D01*
Y190203D01*
X1898061Y190206D01*
G02X1901065I1502J36D01*
G01X1901064Y190203D01*
Y185781D01*
X1901065Y185778D01*
G02X1898061I-1502J-36D01*
G37*
G36*
G01X1776852Y190206D02*
Y185778D01*
G02X1773848I-1502J-36D01*
G01Y190206D01*
G02X1776852I1502J36D01*
G37*
G36*
G01X1652640D02*
Y185778D01*
G02X1649636I-1502J-36D01*
G01Y190206D01*
G02X1652640I1502J36D01*
G37*
G36*
G01X1525423Y185778D02*
X1525424Y185781D01*
Y190203D01*
X1525423Y190206D01*
G02X1528427I1502J36D01*
G01X1528426Y190203D01*
Y185781D01*
X1528427Y185778D01*
G02X1525423I-1502J-36D01*
G37*
G36*
G01X747549D02*
X747550Y185781D01*
Y190203D01*
X747549Y190206D01*
G02X750553I1502J36D01*
G01X750552Y190203D01*
Y185781D01*
X750553Y185778D01*
G02X747549I-1502J-36D01*
G37*
G36*
G01X626340Y190206D02*
Y185778D01*
G02X623336I-1502J-36D01*
G01Y190206D01*
G02X626340I1502J36D01*
G37*
G36*
G01X499123Y185778D02*
X499124Y185781D01*
Y190203D01*
X499123Y190206D01*
G02X502127I1502J36D01*
G01X502126Y190203D01*
Y185781D01*
X502127Y185778D01*
G02X499123I-1502J-36D01*
G37*
G36*
G01X374911D02*
X374912Y185781D01*
Y190203D01*
X374911Y190206D01*
G02X377915I1502J36D01*
G01X377914Y190203D01*
Y185781D01*
X377915Y185778D01*
G02X374911I-1502J-36D01*
G37*
G36*
G01X253702Y190206D02*
Y185778D01*
G02X250698I-1502J-36D01*
G01Y190206D01*
G02X253702I1502J36D01*
G37*
G36*
G01X129490D02*
Y185778D01*
G02X126486I-1502J-36D01*
G01Y190206D01*
G02X129490I1502J36D01*
G37*
G36*
G01X1270436Y184325D02*
X1270439Y184324D01*
X1274861D01*
X1274864Y184325D01*
G02Y181321I36J-1502D01*
G01X1274861Y181322D01*
X1270439D01*
X1270436Y181321D01*
G02Y184325I-36J1502D01*
G37*
G36*
G01X1511414Y180198D02*
X1506986D01*
G02Y183202I-36J1502D01*
G01X1511414D01*
G02Y180198I36J-1502D01*
G37*
G36*
G01X1879361Y170778D02*
X1879362Y170781D01*
Y175203D01*
X1879361Y175206D01*
G02X1882365I1502J36D01*
G01X1882364Y175203D01*
Y170781D01*
X1882365Y170778D01*
G02X1879361I-1502J-36D01*
G37*
G36*
G01X1758152Y175206D02*
Y170778D01*
G02X1755148I-1502J-36D01*
G01Y175206D01*
G02X1758152I1502J36D01*
G37*
G36*
G01X1633940D02*
Y170778D01*
G02X1630936I-1502J-36D01*
G01Y175206D01*
G02X1633940I1502J36D01*
G37*
G36*
G01X1905290Y166690D02*
Y179294D01*
X1914592D01*
Y166694D01*
X1905290Y166690D01*
G37*
G36*
G01X1781076D02*
Y179294D01*
X1790380D01*
Y166694D01*
X1781076Y166690D01*
G37*
G36*
G01X1656864D02*
Y179294D01*
X1666168D01*
Y166694D01*
X1656864Y166690D01*
G37*
G36*
G01X1532652D02*
Y179294D01*
X1541954D01*
Y166694D01*
X1532652Y166690D01*
G37*
G36*
G01X1408440D02*
Y179294D01*
X1417742D01*
Y166694D01*
X1408440Y166690D01*
G37*
G36*
G01X1284226D02*
Y179294D01*
X1293530D01*
Y166694D01*
X1284226Y166690D01*
G37*
G36*
G01X734620D02*
Y179294D01*
X743924D01*
Y166694D01*
X734620Y166690D01*
G37*
G36*
G01X610408D02*
Y179294D01*
X619710D01*
Y166694D01*
X610408Y166690D01*
G37*
G36*
G01X486194D02*
Y179294D01*
X495498D01*
Y166694D01*
X486194Y166690D01*
G37*
G36*
G01X361982D02*
Y179294D01*
X371286D01*
Y166694D01*
X361982Y166690D01*
G37*
G36*
G01X237770D02*
Y179294D01*
X247072D01*
Y166694D01*
X237770Y166690D01*
G37*
G36*
G01X113558D02*
Y179294D01*
X122860D01*
Y166694D01*
X113558Y166690D01*
G37*
G36*
G01X1256786Y169325D02*
X1256789Y169324D01*
X1261211D01*
X1261214Y169325D01*
G02Y166321I36J-1502D01*
G01X1261211Y166322D01*
X1256789D01*
X1256786Y166321D01*
G02Y169325I-36J1502D01*
G37*
G36*
G01X970474Y-46450D02*
Y-70079D01*
G02X919290I-25592J0D01*
G01Y-46456D01*
G02X960345Y-26064I25592J0D01*
G03X960986Y-25741I241J319D01*
G02X970115Y-39262I14801J151D01*
G03X969576Y-39736I-153J-369D01*
G02X970474Y-46450I-24694J-6720D01*
G37*
G36*
G01X558368Y829921D02*
G02I-55120J0D01*
G37*
G36*
G01X1729038D02*
G02I-55121J0D01*
G37*
G54D59*
X111024Y153681D03*
Y606437D03*
Y1059193D03*
X235236Y153681D03*
Y606437D03*
Y1059193D03*
X359449Y153681D03*
Y606437D03*
Y1059193D03*
X483661Y153681D03*
Y606437D03*
Y1059193D03*
X607874Y153681D03*
Y606437D03*
Y1059193D03*
X732087Y153681D03*
Y606437D03*
Y1059193D03*
X949902Y-115157D03*
X1281693Y153681D03*
Y606437D03*
Y1059193D03*
X1405906Y153681D03*
Y606437D03*
Y1059193D03*
X1530118Y153681D03*
Y606437D03*
Y1059193D03*
X1654331Y153681D03*
Y606437D03*
Y1059193D03*
X1778543Y153681D03*
Y606437D03*
Y1059193D03*
X1902756Y153681D03*
Y606437D03*
Y1059193D03*
G54D54*
X118209Y187992D03*
X242421D03*
X615059D03*
X1413091D03*
X1537303D03*
X1909941D03*
X118209Y640748D03*
X242421D03*
X615059D03*
X1413091D03*
X1537303D03*
X1909941D03*
X118209Y1093504D03*
X242421D03*
X615059D03*
X1413091D03*
X1537303D03*
X1909941D03*
G54D55*
X366634Y187992D03*
X490846D03*
X739272D03*
X1288878D03*
X1661516D03*
X1785728D03*
X366634Y640748D03*
X490846D03*
X739272D03*
X1288878D03*
X1661516D03*
X1785728D03*
X366634Y1093504D03*
X490846D03*
X739272D03*
X1288878D03*
X1661516D03*
X1785728D03*
G54D60*
X111024Y302303D03*
Y755059D03*
Y1207815D03*
X235236Y302303D03*
Y755059D03*
Y1207815D03*
X359449Y302303D03*
Y755059D03*
Y1207815D03*
X483661Y302303D03*
Y755059D03*
Y1207815D03*
X607874Y302303D03*
Y755059D03*
Y1207815D03*
X732087Y302303D03*
Y755059D03*
Y1207815D03*
X1098524Y-115157D03*
X1281693Y302303D03*
Y755059D03*
Y1207815D03*
X1405906Y302303D03*
Y755059D03*
Y1207815D03*
X1530118Y302303D03*
Y755059D03*
Y1207815D03*
X1654331Y302303D03*
Y755059D03*
Y1207815D03*
X1778543Y302303D03*
Y755059D03*
Y1207815D03*
X1902756Y302303D03*
Y755059D03*
Y1207815D03*
G54D61*
X79000Y1301900D03*
X1826700Y77600D03*
X1908500Y1346800D03*
G54D58*
X80019Y51968D03*
X127263Y20472D03*
X631200Y51968D03*
X678444Y20472D03*
X1250689Y51969D03*
X1297933Y20472D03*
X1801870Y51969D03*
X1849114Y20472D03*
G54D65*
X942126Y58465D03*
Y346457D03*
Y437598D03*
Y725590D03*
X1110236Y58465D03*
Y346457D03*
Y437598D03*
Y725590D03*
G54D62*
X173228Y1114173D03*
X670079D03*
X1343700D03*
X1840551D03*
G54D64*
X496653Y80906D03*
X1465157D03*
G54D57*
X103642Y36220D03*
X173228Y1062992D03*
X421653Y1141732D03*
X654822Y36220D03*
X670079Y1062992D03*
X1274311Y36220D03*
X1343701Y1062992D03*
X1592126Y1141732D03*
X1825492Y36220D03*
X1840551Y1062992D03*
G54D67*
X1903346Y803937D03*
G54D56*
X31496Y882677D03*
X168307Y646457D03*
X660236D03*
X718110Y820866D03*
X904921Y564961D03*
X1366142Y646457D03*
X1462992Y866929D03*
X1602756Y646457D03*
X1894685Y21654D03*
G54D66*
X975788Y564961D03*
G54D63*
X496654Y110551D03*
X1465158D03*
G54D48*
X1797933Y1282666D03*
Y829910D03*
Y377154D03*
X1549901Y1282666D03*
Y829910D03*
Y377154D03*
X796457Y735444D03*
Y263003D03*
X627263Y1282666D03*
Y829910D03*
Y377154D03*
X131201Y1282666D03*
Y377154D03*
G54D51*
X1102113Y1394115D03*
X1098176Y1401201D03*
X1102113Y1351595D03*
X1098176Y1330335D03*
Y1372855D03*
X1126522Y1330335D03*
X1130459Y1351595D03*
X1102113Y1280729D03*
X1098176Y1301989D03*
X1102113Y1309075D03*
Y1323249D03*
X1130459Y1280729D03*
X1098176Y1259469D03*
Y1231123D03*
X1102113Y1238209D03*
X1126522Y1259469D03*
X1098176Y1188603D03*
X1102113Y1209863D03*
X1098176Y1216949D03*
X1126522Y1188603D03*
X1102113Y1167343D03*
X1098176Y1160257D03*
G54D49*
X1301870Y1282666D03*
Y829910D03*
Y377154D03*
X1181890Y1559854D03*
X1181870Y969280D03*
X1181890Y555917D03*
X961418Y1429932D03*
Y1087413D03*
X379232Y1282666D03*
Y829910D03*
Y377154D03*
X131200Y829910D03*
G54D53*
X1126522Y1401201D03*
X1130459Y1394115D03*
X1126522Y1372855D03*
X1130459Y1323249D03*
Y1309075D03*
X1126522Y1301989D03*
X1130459Y1238209D03*
X1126522Y1231123D03*
Y1216949D03*
X1130459Y1209863D03*
Y1167343D03*
X1126522Y1160257D03*
X1098176Y1002765D03*
X1102113Y1024025D03*
X1098176Y1031111D03*
X1126522D03*
X1130459Y1024025D03*
X1126522Y1002765D03*
G54D50*
X1102113Y1379942D03*
X1098176Y1387028D03*
X1102113Y1408288D03*
Y1365768D03*
X1098176Y1358682D03*
Y1344508D03*
X1102113Y1337422D03*
X1130459D03*
X1126522Y1344508D03*
Y1358682D03*
X1130459Y1365768D03*
X1098176Y1287816D03*
X1102113Y1294902D03*
X1098176Y1316162D03*
Y1273642D03*
X1102113Y1266556D03*
Y1252382D03*
X1098176Y1245296D03*
X1126522D03*
X1130459Y1252382D03*
Y1266556D03*
X1126522Y1273642D03*
X1102113Y1195690D03*
Y1181516D03*
X1098176Y1202776D03*
X1102113Y1224036D03*
X1130459Y1181516D03*
Y1195690D03*
X1098176Y1174430D03*
X1126522D03*
X1116286Y1038198D03*
G54D52*
X1130459Y1408288D03*
X1126522Y1387028D03*
X1130459Y1379942D03*
X1126522Y1316162D03*
X1130459Y1294902D03*
X1126522Y1287816D03*
X1130459Y1224036D03*
X1126522Y1202776D03*
X1102113Y1038198D03*
X1130459D03*
X1098176Y988592D03*
X1102113Y995678D03*
Y1009852D03*
X1098176Y1016938D03*
X1126522D03*
X1130459Y1009852D03*
Y995678D03*
X1126522Y988592D03*
%LPC*%
G75*
G36*
G01X557750Y498350D02*
X543950Y512150D01*
Y535511D01*
X542611Y536850D01*
X525011D01*
X509150Y552711D01*
Y580589D01*
X510385Y581824D01*
X538021D01*
G03X541979I1979J1176D01*
G01X612409D01*
X628750Y565483D01*
Y531111D01*
X616950Y519311D01*
Y512911D01*
X602389Y498350D01*
X557750D01*
G37*
G36*
G01X978889Y1490850D02*
X922356D01*
X909525Y1503681D01*
Y1514236D01*
X908311Y1515450D01*
X892411D01*
X888911Y1518950D01*
X878511D01*
X877750Y1519711D01*
Y1534889D01*
X888511Y1545650D01*
X898536D01*
X921332Y1568446D01*
X974813D01*
X982050Y1561209D01*
Y1530789D01*
X990950Y1521889D01*
Y1502911D01*
X978889Y1490850D01*
G37*
G36*
G01X1464289Y510354D02*
X1414407D01*
X1411050Y513711D01*
Y577189D01*
X1430011Y596150D01*
X1479589D01*
X1518350Y557389D01*
Y536111D01*
X1500089Y517850D01*
X1471785D01*
X1464289Y510354D01*
G37*
%LPD*%
G75*
G54D24*
X127988Y190242D03*
Y185742D03*
Y638498D03*
Y642998D03*
Y1091254D03*
Y1095754D03*
X252200Y190242D03*
Y185742D03*
Y638498D03*
Y642998D03*
Y1091254D03*
Y1095754D03*
X376413Y190242D03*
Y185742D03*
Y638498D03*
Y642998D03*
Y1091254D03*
Y1095754D03*
X500625Y190242D03*
Y185742D03*
Y638498D03*
Y642998D03*
Y1091254D03*
Y1095754D03*
X624838Y190242D03*
Y185742D03*
Y638498D03*
Y642998D03*
Y1091254D03*
Y1095754D03*
X749051Y190242D03*
Y185742D03*
Y638498D03*
Y642998D03*
Y1091254D03*
Y1095754D03*
X1070750Y1224035D03*
X1075250D03*
X1070750Y1209862D03*
X1075250D03*
X1070750Y1216949D03*
X1075250D03*
X1070750Y1231122D03*
X1075250D03*
X1070750Y1238209D03*
X1075250D03*
X1070750Y1245295D03*
X1075250D03*
X1070750Y1301988D03*
X1075250D03*
X1070750Y1309075D03*
X1075250D03*
X1070750Y1316161D03*
X1075250D03*
X1070750Y1323248D03*
X1075250D03*
X1070750Y1294902D03*
X1075250D03*
X1070750Y1330335D03*
X1075250D03*
X1070750Y1387028D03*
X1075250D03*
X1070750Y1394114D03*
X1075250D03*
X1070750Y1401201D03*
X1075250D03*
X1070750Y1408287D03*
X1075250D03*
X1070750Y1415374D03*
X1075250D03*
X1070750Y1379941D03*
X1075250D03*
X1274900Y182823D03*
X1270400D03*
X1261250Y167823D03*
X1256750D03*
X1278500Y638498D03*
Y642998D03*
X1259800Y627998D03*
Y623498D03*
Y1080754D03*
Y1076254D03*
X1278500Y1091254D03*
Y1095754D03*
X1402713Y185742D03*
Y190242D03*
X1380963Y167823D03*
X1385463D03*
X1402713Y638498D03*
Y642998D03*
X1384013Y627998D03*
Y623498D03*
Y1080754D03*
Y1076254D03*
X1402713Y1091254D03*
Y1095754D03*
X1511450Y181700D03*
X1506950D03*
X1508225Y627998D03*
Y623498D03*
Y1080754D03*
Y1076254D03*
X1526925Y185742D03*
Y190242D03*
Y638498D03*
Y642998D03*
Y1091254D03*
Y1095754D03*
X1651138Y185742D03*
Y190242D03*
X1632438Y175242D03*
Y170742D03*
X1651138Y638498D03*
Y642998D03*
X1632438Y627998D03*
Y623498D03*
Y1080754D03*
Y1076254D03*
X1651138Y1091254D03*
Y1095754D03*
X1756650Y175242D03*
Y170742D03*
X1725350Y638498D03*
Y642998D03*
X1731650Y627998D03*
Y623498D03*
X1756650Y1080754D03*
Y1076254D03*
X1775350Y185742D03*
Y190242D03*
Y1091254D03*
Y1095754D03*
X1899563Y185742D03*
Y190242D03*
X1880863Y175242D03*
Y170742D03*
X1899563Y638498D03*
Y642998D03*
X1880863Y627998D03*
Y623498D03*
Y1080754D03*
Y1076254D03*
X1899563Y1091254D03*
Y1095754D03*
G54D44*
X1039845Y1467746D03*
X1026345D03*
X1030845D03*
X1035345D03*
X1039845Y1463246D03*
X1026345D03*
X1030845D03*
X1035345D03*
X1005400Y1463157D03*
X1000900D03*
X996400D03*
X1009900D03*
X1005400Y1467657D03*
X1000900D03*
X996400D03*
X1009900D03*
X1035345Y1476746D03*
X1030845D03*
X1026345D03*
X1039845D03*
Y1472246D03*
X1026345D03*
X1030845D03*
X1035345D03*
X1005400Y1472157D03*
X1000900D03*
X996400D03*
X1009900D03*
Y1476657D03*
X1005400D03*
X1000900D03*
X996400D03*
X1023583Y1489593D03*
X995783D03*
X1000500Y1511400D03*
X1036578Y1511210D03*
X1014690Y1511178D03*
X1010190D03*
X1005690D03*
X1031790Y1511078D03*
X1027290D03*
X1019600Y1511100D03*
X1023583Y1501593D03*
Y1507593D03*
Y1495593D03*
X995783D03*
Y1501593D03*
Y1507593D03*
X1040583Y1517883D03*
X1031799Y1534392D03*
X1031882Y1528985D03*
X1026459Y1528919D03*
X1026376Y1534326D03*
X1014867D03*
X1014950Y1528919D03*
X1020290Y1534392D03*
X1020373Y1528985D03*
X1040500Y1529290D03*
X1040583Y1523883D03*
X1062700Y1463100D03*
X1058200D03*
X1067200D03*
X1062700Y1467600D03*
X1058200D03*
X1067200D03*
X1053700Y1463100D03*
Y1467600D03*
X1062700Y1472100D03*
X1058200D03*
X1067200D03*
Y1476600D03*
X1058200D03*
X1062700D03*
X1053700Y1472100D03*
Y1476600D03*
X1078683Y1489593D03*
X1051383D03*
X1041810Y1511084D03*
X1055310D03*
X1059810D03*
X1064310D03*
X1068810D03*
X1073310D03*
X1078683Y1495593D03*
Y1501593D03*
Y1507593D03*
Y1516593D03*
X1051383Y1495593D03*
Y1501593D03*
Y1507593D03*
X1078683Y1522593D03*
G54D14*
X19712Y1176350D03*
X25000Y1190400D03*
X64487Y201761D03*
X53087Y179561D03*
X49937Y219661D03*
X54437D03*
X58937D03*
X47607Y527511D03*
X61834Y527515D03*
X72500Y508600D03*
X67500D03*
X53087Y632317D03*
X58937Y672417D03*
X54437D03*
X49937D03*
X64487Y654417D03*
X27143Y663071D03*
X27510Y688422D03*
X58175Y981325D03*
X67500Y961355D03*
X72500D03*
X58937Y1125173D03*
X54437D03*
X49937D03*
X64487Y1107173D03*
X53027Y1085073D03*
X39325Y1131400D03*
X26723Y1116038D03*
X36848Y1173600D03*
X27090Y1141389D03*
X31500Y1224000D03*
X39425Y1226200D03*
X30000Y1190400D03*
X37225Y1230100D03*
X45518Y1336366D03*
X41381Y1335567D03*
X95437Y176661D03*
Y181161D03*
X73937Y201661D03*
X78937D03*
X83937D03*
X88937D03*
X85146Y621637D03*
X95437Y633917D03*
X88937Y654417D03*
X83937D03*
X78937D03*
X73937D03*
X101403Y981195D03*
X97063Y973225D03*
X98563Y977225D03*
X114100Y1002600D03*
X99700Y991400D03*
X108063Y991925D03*
X114300Y992362D03*
X104230Y992209D03*
X95537Y1082173D03*
Y1086673D03*
X73937Y1107173D03*
X78937D03*
X83937D03*
X88937D03*
X142687Y248100D03*
X145437Y265561D03*
X166400Y579400D03*
X168103Y569195D03*
X163763Y561225D03*
X165263Y565225D03*
X150253Y709713D03*
X145437Y717617D03*
X142687Y700767D03*
X140364Y749807D03*
X137163Y987125D03*
X130463Y983925D03*
X133063Y1012725D03*
X137063Y993725D03*
X145363Y997741D03*
X131110Y993257D03*
X148400Y1086900D03*
X145437Y1165673D03*
X150862Y1152723D03*
X142687Y1153523D03*
X148300Y1228800D03*
X148311Y1182767D03*
X135422Y1190937D03*
X140422D03*
X163500Y1345200D03*
X188699Y200561D03*
X177399Y179661D03*
X198149Y201661D03*
X203149D03*
X208149D03*
X213149D03*
X174149Y219661D03*
X178649D03*
X183149D03*
X171861Y527469D03*
X186088Y527473D03*
X196712Y508600D03*
X191712D03*
X210263Y546725D03*
X180800Y590600D03*
X207313Y598113D03*
X203763Y581725D03*
X212063Y585741D03*
X197810Y581257D03*
X174763Y579925D03*
X203863Y575125D03*
X181000Y580362D03*
X170930Y580209D03*
X197163Y571925D03*
X185149Y617949D03*
X199763Y600725D03*
X210000Y650000D03*
X182259Y672559D03*
X177759D03*
X173259D03*
X198149Y654417D03*
X203149D03*
X208149D03*
X213149D03*
X199900Y923200D03*
X216712Y961155D03*
X188399Y1102873D03*
X183149Y1125173D03*
X178649D03*
X174149D03*
X177105Y1094839D03*
X195100Y1096800D03*
X198149Y1107173D03*
X203149D03*
X208149D03*
X213149D03*
X219749Y176661D03*
Y181361D03*
X266899Y248011D03*
X219749Y618917D03*
Y623417D03*
X258600Y715500D03*
X266899Y700767D03*
X264731Y749551D03*
X223100Y920600D03*
X239000Y985600D03*
X221712Y961155D03*
X252100Y990100D03*
X244600Y1004600D03*
X261100Y1005700D03*
X227063Y994925D03*
X219749Y1082173D03*
X264864Y1120500D03*
X219749Y1086873D03*
X264594Y1190768D03*
X259594D03*
X312079Y68379D03*
X303029Y68429D03*
X313628Y112926D03*
X303000Y73500D03*
X314370Y118452D03*
X314439Y133669D03*
X312912Y201661D03*
X301612Y179661D03*
X298362Y219661D03*
X302862D03*
X307362D03*
X269649Y266261D03*
X291601Y418503D03*
X292153Y486059D03*
X306388Y486022D03*
X296032Y527469D03*
X310259Y527473D03*
X293763Y582925D03*
X301612Y632417D03*
X307362Y672417D03*
X302862D03*
X298362D03*
X312912Y654417D03*
X274520Y709457D03*
X268100Y982300D03*
X273300Y981700D03*
X280800Y1011900D03*
X281200Y1033000D03*
X271100Y1063200D03*
X281500Y1036744D03*
X307362Y1125173D03*
X302862D03*
X298362D03*
X313232Y1106499D03*
X301327Y1085173D03*
X269649Y1165673D03*
X275385Y1152596D03*
X271165Y1147172D03*
X315500Y1216700D03*
X276100Y1229100D03*
X273243Y1182915D03*
X286925Y1201945D03*
X295900Y1339700D03*
X296100Y1335100D03*
X279900Y1328300D03*
X283700D03*
X286100Y1349659D03*
X292600Y1337367D03*
X289510Y1342259D03*
X354100Y62100D03*
X322500Y68345D03*
X334845Y58745D03*
X361776Y70842D03*
X335081Y104081D03*
X339219Y95188D03*
X339914Y82415D03*
X344304Y82439D03*
X345321Y102400D03*
X347647Y95614D03*
X353001Y114815D03*
X347881Y114881D03*
X351416Y95788D03*
X337641Y114910D03*
X334947Y94605D03*
X342761Y114861D03*
X350441Y117541D03*
X337721Y129821D03*
X323813Y118512D03*
X341114Y123622D03*
X345321Y118921D03*
X323813Y133722D03*
X344062Y176461D03*
X343962Y181161D03*
X322362Y201661D03*
X327362D03*
X332362D03*
X337362D03*
X320474Y379474D03*
X316534D03*
X320474Y363234D03*
X316534D03*
X320925Y485385D03*
X315925D03*
X320925Y508600D03*
X315925D03*
X333682Y621858D03*
X343862Y633917D03*
X322362Y654417D03*
X327362D03*
X332362D03*
X337362D03*
X320474Y832229D03*
X316534D03*
X320925Y938140D03*
X315600Y933600D03*
X335300Y926900D03*
X337100Y972100D03*
X320925Y961355D03*
X315925D03*
X344737Y995637D03*
X350673Y1031200D03*
X344062Y1082073D03*
Y1086773D03*
X322362Y1107173D03*
X327362D03*
X332362D03*
X337362D03*
X331679Y1175800D03*
X377144Y84720D03*
X377944Y95929D03*
X390412Y248011D03*
X386800Y263800D03*
X393862Y719917D03*
X398677Y709385D03*
X391112Y700767D03*
X388788Y749479D03*
X407714Y761291D03*
X398254Y763517D03*
X408672Y1008038D03*
X388888Y1118173D03*
X393679Y1157480D03*
X383191Y1170203D03*
X391112Y1153500D03*
X398527Y1188659D03*
X383849Y1190833D03*
X388849Y1191148D03*
X398527Y1233336D03*
X437124Y201661D03*
X429224Y176300D03*
X446951Y213656D03*
X451951D03*
X456951D03*
X431574Y219661D03*
X427074D03*
X422574D03*
X441645Y288847D03*
Y284647D03*
X456190Y354105D03*
X444687Y379474D03*
X440747D03*
X444687Y363234D03*
X440747D03*
X452800Y420912D03*
X418600Y445462D03*
X421700Y450200D03*
X445138Y487743D03*
X440138D03*
X447533Y475900D03*
X458679Y470700D03*
X450500Y459562D03*
X416303Y486022D03*
X430538Y485985D03*
X420182Y527432D03*
X434409Y527436D03*
X440138Y508600D03*
X445138D03*
X425824Y632317D03*
X457853Y622091D03*
X437224Y654417D03*
X431574Y672417D03*
X427074D03*
X422574D03*
X456574Y654417D03*
X451574D03*
X446574D03*
X444687Y832229D03*
X440747D03*
X444687Y816765D03*
X440747D03*
X445138Y938140D03*
X440138D03*
X435082Y915200D03*
X437600Y917800D03*
X445582Y925352D03*
X449137Y967757D03*
X440138Y961355D03*
X445138D03*
X429613Y1017920D03*
X432657Y1015102D03*
X442600Y998300D03*
X413000Y1054200D03*
X442473Y1068726D03*
X447173D03*
X456919Y1121725D03*
X447919D03*
X452419D03*
X441976Y1107576D03*
X446627Y1112973D03*
X441400Y1169400D03*
X416900Y1221800D03*
X412300Y1326200D03*
X415422Y1352000D03*
X422373Y1359747D03*
X418922Y1356522D03*
X462200Y173109D03*
X468472Y182441D03*
X461951Y213656D03*
X462133Y473300D03*
X481533Y480875D03*
X497351Y531531D03*
X501023Y534941D03*
X472022Y582062D03*
X468174Y633917D03*
X461574Y654417D03*
X465200Y1018200D03*
X506500Y1051900D03*
X504724Y1107073D03*
X505874Y1134773D03*
X506700Y1145973D03*
X508103Y1190557D03*
X509180Y145419D03*
X546009Y187821D03*
X539584Y184694D03*
X542155Y187543D03*
X557057Y220152D03*
X553674Y220121D03*
X550219Y220111D03*
X515324Y252511D03*
X553742Y267705D03*
X510700Y277200D03*
X534905Y354105D03*
X539350Y487659D03*
X534350D03*
X510621Y486059D03*
X524856Y486022D03*
X549279Y513331D03*
X525579Y538331D03*
X557279Y513331D03*
X518700Y548700D03*
X553279Y523331D03*
X514500Y524469D03*
X528727Y524973D03*
X553279Y513331D03*
X530130Y547167D03*
X534350Y508600D03*
X539350D03*
X540000Y583000D03*
X533879Y566031D03*
X548767Y556819D03*
X520579Y553231D03*
X517499Y576931D03*
X527179Y568731D03*
X549937Y632317D03*
X555787Y672417D03*
X551287D03*
X546787D03*
X509996Y716996D03*
X522773Y709638D03*
X515324Y700667D03*
X512884Y749732D03*
X530800Y1028300D03*
X515800Y1028000D03*
X556022Y1042817D03*
X552436Y1042494D03*
X546787Y1125173D03*
X551287D03*
X555787D03*
X549773Y1085173D03*
X514474Y1107073D03*
X519474D03*
X524474D03*
X529474D03*
X509037Y1136700D03*
X524828Y1159231D03*
X522867Y1190284D03*
X513103Y1190557D03*
X522867Y1231097D03*
X520600Y1324100D03*
X536000Y1359826D03*
X541362D03*
X518397Y1360000D03*
X512900Y1345600D03*
X553587Y1346026D03*
X527000Y1340600D03*
X521500Y1342800D03*
X566271Y167387D03*
X561437Y197249D03*
X592767Y179277D03*
X598236Y181981D03*
X582697Y200744D03*
X577697D03*
X572697D03*
X587697D03*
X568899Y379474D03*
X564959D03*
X568899Y363234D03*
X564959D03*
X569529Y502127D03*
X575700Y528831D03*
X563279Y506731D03*
X593079Y516531D03*
Y512531D03*
X585479Y537731D03*
Y543994D03*
X572229Y520081D03*
X580279Y512831D03*
X571529Y562951D03*
X579529D03*
X602779Y552331D03*
X592387Y629417D03*
Y634017D03*
X561437Y654417D03*
X585787D03*
X580787D03*
X575787D03*
X570787D03*
X568899Y832229D03*
X564959D03*
X593365Y877358D03*
X592614Y882300D03*
X569350Y941640D03*
X564350D03*
X569350Y961355D03*
X564350D03*
X571400Y1000100D03*
X592387Y1082173D03*
X561337Y1107173D03*
X592387Y1086873D03*
X570787Y1107173D03*
X575787D03*
X580787D03*
X585787D03*
X600640Y1171000D03*
X592400Y1214456D03*
X607929Y112329D03*
X619171D03*
X639537Y248011D03*
X642287Y266461D03*
X652663Y502400D03*
X647663D03*
X612000Y502300D03*
X624028Y503558D03*
X638263Y503494D03*
X615100Y513287D03*
X627000Y538581D03*
Y542909D03*
X609334Y538306D03*
Y543306D03*
X619560Y547201D03*
X627863Y522000D03*
X642509Y520667D03*
X652663Y516600D03*
X647663D03*
X637213Y582155D03*
X623236Y562574D03*
X642287Y719817D03*
X647207Y709555D03*
X639537Y700767D03*
X637318Y749649D03*
X645200Y1067800D03*
X636803Y1167864D03*
X642942Y1156818D03*
X632603Y1136225D03*
X647716Y1154150D03*
X639537Y1153523D03*
X627632Y1217300D03*
X647126Y1189513D03*
X632316Y1190474D03*
X637316D03*
X687566Y109568D03*
X663449Y115606D03*
X690807Y103298D03*
X677450Y185669D03*
X685250Y199493D03*
X699950Y200846D03*
X694950D03*
X674313Y220374D03*
X669813D03*
X689232Y355251D03*
X693112Y385976D03*
X689172D03*
Y358978D03*
X658646Y515180D03*
X658681Y571798D03*
X654681D03*
X683341Y580479D03*
X689747D03*
X682000Y628449D03*
X685550Y654417D03*
X679929Y673058D03*
X675429D03*
X670929D03*
X700000Y654417D03*
X695000D03*
X658574Y930100D03*
X677457Y944796D03*
X688563Y961355D03*
X693563D03*
X663800Y1018300D03*
X682200Y1026500D03*
X674300Y1001620D03*
X685250Y1102873D03*
X680000Y1125173D03*
X675500D03*
X671000D03*
X674700Y1098500D03*
X695000Y1107173D03*
X700000D03*
X664000Y1278100D03*
X673000Y1354100D03*
X747242Y197553D03*
X717188Y176461D03*
X716600Y181161D03*
X709950Y200846D03*
X704950D03*
X705348Y478425D03*
X716600Y629417D03*
Y633917D03*
X710000Y654417D03*
X705000D03*
X724283Y860689D03*
X737984Y861689D03*
X741883Y861389D03*
X733883Y935689D03*
X736883Y938689D03*
Y929189D03*
Y933689D03*
X747383Y924689D03*
X733883Y940689D03*
X736462Y948996D03*
X736883Y943189D03*
X716600Y1081973D03*
Y1086673D03*
X705000Y1107173D03*
X710000D03*
X728174Y1275611D03*
X725678Y1272799D03*
X722790Y1270557D03*
X720446Y1267427D03*
X731500Y1277811D03*
X757020Y159692D03*
X758619Y168537D03*
X767405Y210364D03*
X763188Y172500D03*
X789739Y365493D03*
X754500Y668741D03*
X755000Y677700D03*
X765124Y864089D03*
X766707Y872260D03*
X762453Y872413D03*
X765025Y867802D03*
X757664Y868974D03*
X753893Y912630D03*
X776400Y956500D03*
X780800Y959300D03*
X786800Y1016000D03*
X784000Y1024000D03*
X759500Y1056100D03*
X779535Y1180469D03*
X792263Y1178661D03*
Y1174461D03*
Y1170261D03*
X752500Y1167500D03*
X756250Y1151750D03*
X784544Y1210178D03*
Y1205978D03*
X779535Y1193469D03*
Y1189269D03*
Y1184669D03*
X797177Y1189537D03*
X797225Y1185337D03*
X792263Y1182861D03*
X792336Y1319537D03*
X782230Y1323670D03*
X769728Y1325747D03*
X785340Y1320410D03*
X789549Y1322310D03*
X777009Y1322690D03*
X781290Y1328490D03*
X772900Y1328550D03*
X790290Y1328410D03*
X785640Y1328370D03*
X796848Y1469724D03*
X829921Y-458D03*
X825984D03*
X833724Y-3346D03*
X833671Y254D03*
X806299Y-458D03*
X802362D03*
X814173D03*
X810236D03*
X822047D03*
X818110D03*
X845661Y-3642D03*
X843463Y530D03*
X806314Y35952D03*
X802350Y35923D03*
X842470Y41295D03*
X841733Y36654D03*
X818300Y39845D03*
X814300D03*
Y43845D03*
X818300D03*
X810301Y78654D03*
X805301D03*
X802801Y75654D03*
X807801D03*
X812801D03*
X846400Y473900D03*
X839500Y508500D03*
X809015Y661000D03*
X804015D03*
X808920Y652340D03*
Y656460D03*
X806515Y664000D03*
X802036Y1164244D03*
X803438Y1139700D03*
X809600Y1236300D03*
X804600D03*
X802100Y1233300D03*
X807100D03*
X812100D03*
X806952Y1460496D03*
X806568Y1464275D03*
X802433Y1461619D03*
X800900Y1465234D03*
X800462Y1469231D03*
X834813Y1528889D03*
X834974Y1533243D03*
X886322Y69D03*
X867080Y393D03*
X886427Y3802D03*
X873892Y287D03*
X886418Y-7350D03*
X849484Y649D03*
X886351Y-3735D03*
X857513Y659D03*
X885448Y37380D03*
X877265Y52540D03*
X881265D03*
X885265D03*
X873265D03*
X869265D03*
X869459Y56626D03*
Y61626D03*
X869044Y66985D03*
X873044D03*
X877139Y66926D03*
X885265Y60540D03*
Y56540D03*
X881750Y37397D03*
X858496Y37121D03*
X854180Y36996D03*
X852995Y40965D03*
X856995D03*
X886073Y78824D03*
X885464Y83201D03*
X878549Y78905D03*
Y82905D03*
X869044Y70985D03*
X873044D03*
X882549Y76905D03*
Y80905D03*
X872796Y251714D03*
X881549Y326304D03*
X890982Y349498D03*
X874800Y355798D03*
X887100Y359100D03*
X887500Y378495D03*
X875132Y399200D03*
X878732D03*
Y395600D03*
X875132D03*
X878732Y392000D03*
X875132D03*
X880932Y406400D03*
Y402800D03*
X877332Y406400D03*
Y402800D03*
X874807Y375193D03*
X866276Y454900D03*
X866317Y446725D03*
X880932Y410000D03*
X877332D03*
X857300Y454300D03*
X862000Y453600D03*
X852000Y454200D03*
X866321Y451300D03*
X878500Y476000D03*
X878193Y467707D03*
X866278Y459562D03*
X870600Y476900D03*
X851800Y477200D03*
X874715Y707651D03*
X871115D03*
X867515D03*
X884700Y705200D03*
X881100D03*
X877500D03*
X887600Y811900D03*
X891200Y838200D03*
X878673Y804527D03*
X874569Y811300D03*
X885882Y861618D03*
X894965Y843500D03*
X877673Y868873D03*
X888962Y843262D03*
X873647Y861653D03*
X882333Y896320D03*
X895616Y985932D03*
X863800Y1309876D03*
X872164Y1350464D03*
X873259Y1365805D03*
X872181Y1354764D03*
X886792Y1404100D03*
X873918Y1411149D03*
X873800Y1418200D03*
X871432Y1420932D03*
X874900Y1421900D03*
X877406Y1419124D03*
X875740Y1415070D03*
X882226Y1404197D03*
X873694Y1404575D03*
X873700Y1375746D03*
X873570Y1380401D03*
X872192Y1424492D03*
X882000Y1432600D03*
X870921Y1432300D03*
X893158Y1516542D03*
X888800Y1493500D03*
X876514Y1514948D03*
X863851Y1501681D03*
X877828Y1500379D03*
X892966Y1508549D03*
X893036Y1512600D03*
X877946Y1496527D03*
X876096Y1505499D03*
X889002Y1489638D03*
X873972Y1472467D03*
X873922Y1477766D03*
X860179Y1491170D03*
X892682Y1520718D03*
X893020Y1566530D03*
X876200Y1553900D03*
X892700Y1543900D03*
X892558Y1528458D03*
X889300Y1551000D03*
X876190Y1537187D03*
X876100Y1549000D03*
X876200Y1558400D03*
X892700Y1524700D03*
X848551Y1542440D03*
X922687Y93D03*
X928138Y-8453D03*
X942000Y752850D03*
X897000Y839000D03*
X903000Y842500D03*
X920810Y902210D03*
X928100Y900650D03*
X900615Y909723D03*
X902571Y906534D03*
X903368Y934568D03*
X904594Y931141D03*
X916204Y938572D03*
X917550Y934742D03*
X901540Y937712D03*
X896679Y927505D03*
X896420Y916712D03*
X898468Y912970D03*
X931085Y936172D03*
X941274Y900845D03*
X934142Y974344D03*
X939481Y980230D03*
X912994Y971921D03*
X910397Y979189D03*
X902991Y982230D03*
X909826Y982874D03*
X905271Y974586D03*
X899846Y971468D03*
X898617Y975434D03*
X895837Y978389D03*
X896629Y982285D03*
X935623Y971054D03*
X904601Y998556D03*
X910040Y1006613D03*
X911807Y1002342D03*
X919656Y998764D03*
X939544Y1003485D03*
X903442Y1003265D03*
X896371Y1002112D03*
X936378Y1035722D03*
X920770Y1067389D03*
X921149Y1062424D03*
X914948Y1063255D03*
X908477Y1061823D03*
X910387Y1055344D03*
X904875Y1051177D03*
X896500Y1341800D03*
X936959Y1360143D03*
X896212Y1345788D03*
X895900Y1390100D03*
X896200Y1386000D03*
X896100Y1393800D03*
X896200Y1397900D03*
Y1405300D03*
X896100Y1401600D03*
X923829Y1389012D03*
X936994Y1379895D03*
X927601Y1384433D03*
X923486Y1384268D03*
X906600Y1461600D03*
X909400Y1459200D03*
X910000Y1464900D03*
X905500Y1467161D03*
X932500Y1493200D03*
X926500Y1499700D03*
X918500D03*
X942000Y1499500D03*
X922500Y1499700D03*
X908742Y1477427D03*
X908542Y1481127D03*
X922500Y1509700D03*
X906000Y1543700D03*
X918505Y1530405D03*
X918800Y1534500D03*
X940750Y1549200D03*
X900000Y1526500D03*
X897400Y1574000D03*
X897038Y1577600D03*
X911516Y1573202D03*
X911616Y1576802D03*
X911710Y1582375D03*
X911094Y1585923D03*
X924059Y1647700D03*
X981700Y-115500D03*
X976713Y-115570D03*
X991713Y-115413D03*
X989316Y-94984D03*
X992185Y-54411D03*
X989050Y-70850D03*
X990565Y130230D03*
Y135230D03*
Y125230D03*
X985688Y362549D03*
X977794Y695103D03*
X952200Y742600D03*
X957100Y742900D03*
X977622Y699464D03*
X953200Y736700D03*
X956900Y737600D03*
X949048Y755225D03*
X952476Y753652D03*
X951300Y747900D03*
X956200Y748200D03*
X957320Y769818D03*
X947866Y763541D03*
X957629Y766231D03*
X952820Y769518D03*
X944500Y760750D03*
X961100Y931640D03*
X960503Y936185D03*
X967583Y933607D03*
X968698Y928957D03*
X974484Y935078D03*
X976419Y931628D03*
X976460Y927891D03*
X981679Y936678D03*
X976213Y938846D03*
X966000Y937500D03*
X953013Y960147D03*
X947174Y957150D03*
X979020Y960000D03*
Y956200D03*
X973900Y960000D03*
Y956200D03*
X968780Y960000D03*
Y956200D03*
X987734Y979575D03*
X951200Y1030700D03*
X946700D03*
X947759Y998726D03*
X961220Y1001600D03*
Y1005400D03*
X966340Y1001600D03*
Y1005400D03*
X971460Y1001600D03*
Y1005400D03*
X974020Y1026200D03*
Y1022400D03*
X968900Y1026200D03*
Y1022400D03*
X963780Y1026200D03*
Y1022400D03*
X956600Y1001700D03*
Y1005700D03*
X964537Y1160310D03*
X958870Y1163617D03*
X962941Y1165929D03*
X967497Y1168802D03*
X957871Y1171219D03*
X963000Y1174427D03*
X969463Y1177599D03*
X972924Y1158033D03*
X954395Y1145604D03*
X982387Y1183598D03*
X951525Y1369107D03*
X955500Y1369000D03*
X944921Y1515200D03*
X988624Y1502923D03*
X951815Y1491459D03*
X969198Y1505851D03*
X969472Y1501978D03*
X950300Y1499500D03*
X954700Y1524100D03*
Y1530363D03*
X974787Y1525100D03*
Y1529300D03*
X948750Y1549200D03*
X979963Y1545689D03*
X1004213Y-95837D03*
X998045Y-79300D03*
X993816Y-95184D03*
X1036713Y-115500D03*
X1007582Y-39418D03*
X1000300Y-74200D03*
X1032080Y-45980D03*
X1004082Y-38200D03*
X1000418Y-69982D03*
X993000Y-60600D03*
X1019118Y-34382D03*
X1019082Y-71000D03*
X1026717Y-11646D03*
X1021086Y-11682D03*
X1010650Y49950D03*
Y67650D03*
X1030775Y130016D03*
X1030890Y137780D03*
X993565Y137730D03*
Y132730D03*
Y127730D03*
X1030774Y133840D03*
X1030758Y126274D03*
X1030825Y122335D03*
X1020250Y357188D03*
X1040180Y437510D03*
X1038215Y877191D03*
X1034271Y876911D03*
X1011100Y904600D03*
X1025000Y897700D03*
X1036431Y929752D03*
X1037083Y933300D03*
X1016842Y916445D03*
X1035947Y948800D03*
X1028657Y1009103D03*
X1020654Y1023940D03*
X1018094Y1021240D03*
X1015534Y1023840D03*
X1007849Y1033743D03*
X996600D03*
X1012974Y1021240D03*
X1013700Y1007640D03*
X1009509Y1009850D03*
X1037282Y995028D03*
X1005294Y997940D03*
Y1001740D03*
X1010414Y997940D03*
Y1001740D03*
X1023214Y1007140D03*
X1007372Y1023832D03*
X1017194Y1033840D03*
X1026900Y1129466D03*
X1022400Y1129183D03*
X1036160Y1095500D03*
Y1091700D03*
Y1111900D03*
X994923Y1137488D03*
X995948Y1184250D03*
X1017354Y1196124D03*
X1021061Y1198543D03*
X1016835Y1323916D03*
X1025335Y1324216D03*
X1016672Y1338228D03*
X1025284Y1341216D03*
X1025335Y1337616D03*
Y1330916D03*
X1016600Y1332000D03*
X1033000Y1416125D03*
X1028000Y1404700D03*
Y1411000D03*
X1031500Y1408000D03*
X1020854Y1455075D03*
X1016854D03*
X1051713Y-114887D03*
X1056713Y-115413D03*
X1086713Y-115570D03*
X1081713D03*
X1071713D03*
X1066713D03*
X1041713Y-115465D03*
X1085300Y-90700D03*
X1079455Y-30742D03*
X1043000Y-67600D03*
X1043112Y-34912D03*
X1066600Y-72800D03*
X1066225Y-40278D03*
X1054593Y-51122D03*
X1078900Y-45782D03*
X1085800Y-57100D03*
X1070918Y-73618D03*
X1043303Y-27685D03*
X1045873Y-24660D03*
X1043513Y-21696D03*
X1077505Y22405D03*
X1076418Y31082D03*
X1076944Y35182D03*
X1077260Y42612D03*
X1077400Y52000D03*
X1077082Y38982D03*
X1076905Y46195D03*
X1076299Y27282D03*
X1054800Y22405D03*
X1041500Y382858D03*
X1078100Y392600D03*
Y397600D03*
Y402600D03*
X1072600Y392500D03*
Y397500D03*
Y402500D03*
X1045292Y384688D03*
X1074425Y447225D03*
X1071950Y453288D03*
X1072600Y407500D03*
X1078100Y407600D03*
X1043674Y451921D03*
X1043500Y446600D03*
X1042800Y442000D03*
X1069018Y456900D03*
X1065985Y460500D03*
X1054419Y839493D03*
Y828081D03*
X1050763Y829163D03*
X1086600Y833200D03*
X1044101Y927130D03*
X1083633Y932172D03*
X1073408Y942399D03*
X1058571Y943852D03*
X1053099Y1021657D03*
X1048512Y1021378D03*
X1041616Y997225D03*
X1069000Y1067100D03*
X1083355Y1125903D03*
X1070155D03*
X1048960Y1113900D03*
Y1117700D03*
X1041280Y1121500D03*
Y1113900D03*
Y1117700D03*
X1081078Y1095362D03*
X1083660Y1092700D03*
X1041280Y1095500D03*
Y1091700D03*
Y1100500D03*
X1048960Y1095500D03*
Y1091700D03*
Y1099300D03*
X1054080Y1113900D03*
Y1117700D03*
X1068700Y1108700D03*
X1083355Y1116103D03*
X1070155D03*
X1075600Y1179090D03*
X1053743Y1174221D03*
X1046900Y1168000D03*
X1052522Y1145153D03*
X1076032Y1191144D03*
X1070000Y1184100D03*
X1079500Y1276100D03*
X1047000Y1258687D03*
X1051300Y1253300D03*
X1077300Y1271700D03*
X1042343Y1324216D03*
X1048251Y1349992D03*
X1046372Y1356326D03*
X1042343Y1337616D03*
X1042443Y1342668D03*
X1042343Y1330916D03*
X1076754Y1455075D03*
X1072754D03*
X1044654D03*
X1048654D03*
X1100929Y-90371D03*
X1116600Y-85538D03*
X1106300Y-94800D03*
X1089318Y-91682D03*
X1101246Y-31005D03*
X1124024Y-30840D03*
X1128765Y-34297D03*
X1094200Y-38400D03*
X1111254Y-31020D03*
X1105328Y-31005D03*
X1094300Y-60300D03*
X1103300Y-60000D03*
X1115603Y-60293D03*
X1134110Y176500D03*
X1136203Y167600D03*
X1089300Y836100D03*
X1119419Y888607D03*
X1116419Y896107D03*
Y891107D03*
X1119419Y893607D03*
Y898607D03*
X1110447Y944217D03*
X1105447D03*
X1100447D03*
X1102947Y947217D03*
X1107947D03*
X1091400Y1070900D03*
X1091494Y1075994D03*
X1097800Y1070700D03*
X1097500Y1075100D03*
X1103800Y1070600D03*
Y1075600D03*
X1128900Y1067200D03*
X1119500Y1125100D03*
X1115000D03*
X1123600Y1096400D03*
X1123838Y1092800D03*
X1123600Y1100000D03*
X1133981Y1096283D03*
X1134002Y1092600D03*
X1134103Y1099881D03*
X1137436Y1124750D03*
X1128800Y1125100D03*
X1092200Y1125800D03*
X1103064Y1113626D03*
X1099020Y1112276D03*
X1096460Y1115125D03*
X1092742Y1113462D03*
X1134100Y1433300D03*
X1146768Y-31238D03*
X1139808Y-31171D03*
X1149699Y-35153D03*
X1142293Y-37522D03*
X1181568Y55168D03*
X1181868Y50568D03*
Y45568D03*
X1181568Y60168D03*
X1178268Y64068D03*
X1183268D03*
X1178268Y85068D03*
Y69068D03*
Y89068D03*
X1183268Y85068D03*
Y69068D03*
Y89068D03*
X1178656Y104637D03*
X1176952Y93390D03*
X1140550Y179200D03*
X1142800Y174637D03*
X1140500Y171400D03*
X1171749Y259163D03*
X1175400Y258800D03*
X1176300Y284500D03*
X1180953Y284800D03*
X1185588Y285035D03*
X1185000Y281343D03*
X1176100Y270603D03*
X1176300Y288600D03*
X1169768Y730300D03*
Y723100D03*
Y726700D03*
X1175568Y712300D03*
X1171968D03*
X1175568Y715900D03*
X1171968D03*
X1173368Y730300D03*
X1171968Y719500D03*
X1175568D03*
X1173368Y726700D03*
Y723100D03*
X1138198Y832424D03*
X1172736Y1031786D03*
X1177036Y1032086D03*
X1170140Y1043939D03*
X1152880Y1097672D03*
X1152682Y1091138D03*
X1149984Y1115804D03*
X1143550Y1120317D03*
X1139524Y1121817D03*
X1152800Y1223062D03*
X1152700Y1216213D03*
X1150420Y1229800D03*
X1181400Y1266100D03*
X1184000Y1260100D03*
X1149823Y1233373D03*
X1144000Y1310000D03*
X1150232Y1316358D03*
X1154500Y1327500D03*
X1150911Y1329500D03*
X1147900Y1421500D03*
X1143900Y1431000D03*
X1142400Y1427700D03*
X1146002Y1427906D03*
X1145007Y1424446D03*
X1148556Y1425056D03*
X1188268Y64068D03*
Y85068D03*
Y69068D03*
Y89068D03*
X1215795Y181242D03*
X1215600Y261800D03*
X1219962Y244739D03*
X1186600Y253200D03*
X1215547Y246355D03*
X1194700Y261700D03*
X1189700Y308527D03*
X1190200Y285023D03*
X1201835Y305319D03*
X1193800Y307857D03*
X1198100Y306858D03*
X1194600Y288237D03*
X1197000Y279400D03*
X1226045Y431102D03*
X1194000Y1037900D03*
X1232842Y1140722D03*
X1198130Y1151410D03*
X1205303Y1227604D03*
X1250016Y247017D03*
X1253300Y227700D03*
X1262075Y297100D03*
X1250500Y266600D03*
X1239362Y524168D03*
X1253511Y517606D03*
X1264878Y508068D03*
X1268400Y716100D03*
X1265891Y699583D03*
X1263250Y823436D03*
X1243200Y933700D03*
X1259808Y927260D03*
X1271296Y986867D03*
X1274413Y984613D03*
X1279599Y976407D03*
X1253338Y980784D03*
X1253975Y970147D03*
X1264269Y981248D03*
X1263618Y990606D03*
X1268378Y990608D03*
X1239900Y1024000D03*
X1256142Y1029316D03*
X1252400Y1054100D03*
X1272755Y1137293D03*
X1260300Y1169000D03*
X1240314Y1139741D03*
X1268948Y1150173D03*
X1254800Y1269600D03*
X1240276Y1356700D03*
X1323829Y55929D03*
X1328295Y55800D03*
X1320055Y68000D03*
X1304563Y100771D03*
X1299569Y100639D03*
X1312263Y95463D03*
X1327921Y78900D03*
X1308228Y93399D03*
X1315961Y98112D03*
X1314794Y162944D03*
X1324134Y126967D03*
X1313127Y120839D03*
X1315118Y126967D03*
X1324207Y138756D03*
X1315102Y137903D03*
X1330807Y181473D03*
X1311750Y187911D03*
X1326637Y226568D03*
X1316637D03*
X1321637D03*
X1326500Y627917D03*
X1311750Y640667D03*
X1312000Y615417D03*
X1318000Y680417D03*
X1323000D03*
X1328000D03*
X1316000Y772200D03*
X1310500Y774700D03*
X1312767Y885535D03*
X1286000Y982200D03*
X1284695Y956586D03*
X1326500Y1080673D03*
X1317400Y1068000D03*
X1309600Y1068173D03*
X1311750Y1093423D03*
X1328000Y1133173D03*
X1318000D03*
X1323000D03*
X1351200Y68600D03*
X1359350Y66350D03*
X1358355Y81488D03*
X1338215Y107586D03*
X1336034Y82542D03*
X1334383Y75892D03*
X1340961Y78811D03*
X1343521Y85472D03*
X1347607Y101337D03*
X1346081Y80671D03*
X1348641Y83326D03*
X1352351Y101724D03*
X1350779Y106496D03*
X1348641Y110550D03*
X1333281Y85133D03*
X1341922Y105649D03*
X1354500Y75400D03*
X1349931Y138361D03*
X1338400Y126015D03*
X1333988Y161471D03*
X1358971Y129978D03*
X1362685Y130109D03*
X1351665Y128325D03*
X1343112Y128997D03*
X1364017Y123277D03*
X1337662Y137188D03*
X1334500Y202548D03*
Y207548D03*
Y212548D03*
Y217548D03*
X1372274Y272874D03*
X1355991Y275272D03*
X1374338Y292900D03*
X1358573Y290900D03*
X1375700Y413400D03*
X1357316Y542311D03*
X1346057Y529857D03*
X1338100Y520300D03*
X1353500Y518900D03*
X1359882Y508014D03*
X1364882D03*
X1336000Y627000D03*
X1334000Y666417D03*
Y661917D03*
Y657417D03*
Y652917D03*
X1373553Y700994D03*
X1347600Y734078D03*
X1344062Y737800D03*
X1354500Y747304D03*
X1360920Y749829D03*
X1334300Y771200D03*
X1338729Y776131D03*
X1338700Y771500D03*
X1334329Y775831D03*
X1373519Y761900D03*
X1341219Y933282D03*
X1346080Y907004D03*
X1378100Y972100D03*
X1339404Y969600D03*
X1353762Y969886D03*
X1367382Y961355D03*
X1362382D03*
X1349829Y1014840D03*
X1365551Y1028250D03*
X1361074Y1114565D03*
X1334500Y1104700D03*
Y1111173D03*
Y1116173D03*
Y1121173D03*
X1360238Y1143867D03*
X1370716Y1148037D03*
X1351321Y1152553D03*
X1355733Y1241900D03*
X1369600Y1330100D03*
X1373700Y1330000D03*
X1365551Y1353500D03*
X1427663Y167032D03*
X1384475Y255839D03*
X1384713Y323200D03*
X1414882Y397271D03*
X1395300Y438500D03*
X1418225Y421700D03*
X1407936Y552099D03*
Y548099D03*
X1425200Y540100D03*
X1414319Y523900D03*
X1413400Y575000D03*
X1396297Y573397D03*
X1421239Y558029D03*
X1396297Y579803D03*
X1421239Y562229D03*
X1383952Y717435D03*
X1392355Y886696D03*
X1391000Y932400D03*
X1380300Y930200D03*
X1384800Y1002666D03*
X1383899Y1166690D03*
X1388500Y1224900D03*
X1381800Y1329600D03*
X1463804Y138605D03*
X1436204Y159247D03*
X1435963Y183833D03*
X1450713Y173049D03*
X1456373Y168971D03*
X1458764Y212625D03*
Y208025D03*
Y203425D03*
X1442213Y227661D03*
X1447213D03*
X1452213D03*
X1458764Y217225D03*
X1444238Y349852D03*
X1439654D03*
X1431909Y359311D03*
X1463000Y490638D03*
X1442500Y548400D03*
X1456450Y529600D03*
X1448450D03*
X1452279Y563600D03*
X1464700Y585600D03*
X1470000Y580000D03*
X1460274Y592498D03*
X1442500Y554700D03*
X1455750Y572350D03*
X1474700Y569100D03*
X1447700Y579600D03*
X1474700Y579100D03*
X1450713Y627817D03*
X1435963Y640667D03*
X1455202Y618557D03*
X1436213Y615417D03*
X1442213Y680417D03*
X1447213D03*
X1452213D03*
X1458713Y658417D03*
Y663417D03*
Y668417D03*
Y652217D03*
X1474083Y764750D03*
X1471608Y768500D03*
X1435300Y882700D03*
X1440500Y893500D03*
X1448000Y910000D03*
X1463616Y969265D03*
X1451800Y1004700D03*
X1450713Y1080673D03*
X1446213Y1062300D03*
X1436213Y1068173D03*
X1442213Y1132173D03*
X1447213D03*
X1452213D03*
X1439750Y1096673D03*
X1461713Y1123173D03*
Y1118173D03*
Y1113173D03*
X1461700Y1107200D03*
X1470953Y1152427D03*
X1475953D03*
X1467000Y1221800D03*
X1473600Y1242777D03*
X1511177Y125412D03*
X1499775Y248061D03*
X1508925Y323200D03*
X1481938Y489926D03*
X1479212Y535612D03*
X1494100Y526400D03*
X1507900Y539100D03*
X1500600Y523300D03*
X1502400Y544100D03*
X1497849Y545264D03*
X1486594Y508098D03*
X1491594D03*
X1513200Y519700D03*
X1509800Y516100D03*
X1509911Y553511D03*
X1478700Y579100D03*
X1502400Y554100D03*
X1494400Y560400D03*
Y556100D03*
X1500539Y739639D03*
X1498000Y743000D03*
X1505900Y717600D03*
X1495480Y704558D03*
X1489000Y723000D03*
X1476558Y759088D03*
X1479033Y762259D03*
X1486600Y786559D03*
X1505900Y930400D03*
X1521200Y928000D03*
X1503394Y968179D03*
X1477974Y970044D03*
X1491594Y961355D03*
X1486594D03*
X1484000Y992315D03*
X1481500Y995758D03*
X1478194Y1017166D03*
X1481529Y1030500D03*
X1485608Y1113628D03*
X1504200Y1171300D03*
X1485833Y1140369D03*
X1495900Y1149000D03*
X1491662Y1351300D03*
X1494662Y1336000D03*
X1497200Y1342500D03*
X1501600Y1342300D03*
X1560425Y162661D03*
X1560175Y187911D03*
X1566425Y227661D03*
X1571425D03*
X1568500Y438500D03*
Y544100D03*
X1568000Y548500D03*
X1555175Y642667D03*
X1560425Y615417D03*
X1566425Y677417D03*
X1571425D03*
X1565593Y654856D03*
X1565618Y660773D03*
Y665773D03*
Y670773D03*
X1526000Y728000D03*
X1570500Y888400D03*
X1570425Y1062000D03*
X1560425Y1068173D03*
X1547800Y1098819D03*
X1552800D03*
X1557800D03*
X1562800D03*
X1556231Y1134920D03*
X1558650Y1217426D03*
X1574925Y175061D03*
X1579371Y166019D03*
X1582925Y210661D03*
Y205661D03*
Y200661D03*
X1576425Y227661D03*
X1621100Y244661D03*
X1582925Y215661D03*
X1586596Y518723D03*
X1600745Y517561D03*
X1615807Y508600D03*
X1610807D03*
X1574925Y627817D03*
X1578926Y618657D03*
X1576425Y677417D03*
X1620469Y697517D03*
X1584800Y895800D03*
X1587400Y912200D03*
X1608200Y914400D03*
X1618200Y916800D03*
X1574576Y976700D03*
X1615494Y973179D03*
X1587829Y969191D03*
X1602187Y969970D03*
X1615807Y961355D03*
X1610807D03*
X1580381Y1007066D03*
X1602400Y1019366D03*
X1620059Y1032932D03*
X1574925Y1080673D03*
X1603425Y1105040D03*
Y1100040D03*
X1598425Y1102440D03*
Y1107440D03*
X1620059Y1128071D03*
X1615909Y1150262D03*
X1613400Y1236500D03*
X1622738Y264938D03*
X1621138Y719238D03*
X1643344Y887455D03*
X1646013Y884255D03*
X1639644Y889755D03*
X1633600Y936300D03*
X1621787Y917108D03*
X1636400Y925800D03*
X1629094Y975179D03*
X1624198Y1111309D03*
X1633138Y1165673D03*
X1635688Y1153773D03*
X1624500Y1349100D03*
X1684638Y162661D03*
X1684388Y187911D03*
X1699138Y175061D03*
X1703584Y166019D03*
X1707138Y210661D03*
Y205661D03*
Y200661D03*
X1690638Y227661D03*
X1695638D03*
X1700638D03*
X1707138Y215661D03*
X1711061Y518470D03*
X1684388Y638324D03*
X1699138Y627917D03*
X1705000Y618667D03*
X1684638Y615417D03*
X1699638Y675417D03*
X1689638D03*
X1694638D03*
X1707100Y652500D03*
X1707138Y658417D03*
Y663417D03*
Y668417D03*
X1692100Y923600D03*
X1704010Y898000D03*
X1674814Y961977D03*
X1677056Y954636D03*
X1680012Y952402D03*
X1685047Y1014966D03*
X1680087Y1023983D03*
X1671422Y1009266D03*
X1690279Y1011526D03*
X1691771Y1035163D03*
X1699138Y1080573D03*
X1685100Y1054000D03*
X1679300Y1043169D03*
X1694638Y1063600D03*
X1684638Y1068173D03*
X1700638Y1131673D03*
X1695638D03*
X1690638D03*
X1684388Y1091723D03*
X1707138Y1111173D03*
Y1116173D03*
Y1121173D03*
X1707200Y1105200D03*
X1702838Y1215300D03*
X1710617Y1231429D03*
X1715049Y1234000D03*
X1746400Y244561D03*
X1747550Y265000D03*
X1725100Y519300D03*
X1740019Y508600D03*
X1735019D03*
X1752000Y929200D03*
X1755010Y966285D03*
X1740019Y961355D03*
X1735019D03*
X1738863Y985225D03*
X1755900Y1014600D03*
X1740499Y1008223D03*
X1749863Y1003925D03*
X1756100Y1004362D03*
X1746030Y1004209D03*
X1737241Y997843D03*
X1740363Y989225D03*
X1733245Y1115503D03*
X1751400Y1173900D03*
X1732768Y1141697D03*
X1748100Y1153673D03*
X1718117Y1152553D03*
X1723117D03*
X1755900Y1212704D03*
X1740000Y1346900D03*
X1808850Y162661D03*
X1808600Y187911D03*
Y640667D03*
X1808850Y615417D03*
X1766721Y720500D03*
X1813851Y927406D03*
X1768692Y966073D03*
X1797463Y968652D03*
X1806077Y961860D03*
X1782666Y961344D03*
X1777666D03*
X1783778Y970371D03*
X1774863Y1024725D03*
X1788726Y1034726D03*
X1778863Y1005725D03*
X1787163Y1009741D03*
X1772863Y1005304D03*
X1778963Y999125D03*
X1772263Y995925D03*
X1812050Y1071223D03*
X1805250Y1067973D03*
X1841021Y152968D03*
X1845517Y158475D03*
X1856219Y201661D03*
X1823350Y175161D03*
X1827796Y166019D03*
X1831350Y210661D03*
Y205661D03*
Y200661D03*
X1850669Y219661D03*
X1846169D03*
X1841669D03*
X1824850Y227661D03*
X1819850D03*
X1814850D03*
X1831350Y215661D03*
X1834896Y518597D03*
X1849045Y517435D03*
X1859232Y508600D03*
X1823350Y627917D03*
X1827667Y618703D03*
X1840855Y606200D03*
X1845417Y611231D03*
X1841669Y672417D03*
X1846169D03*
X1850669D03*
X1814850Y680417D03*
X1819850D03*
X1824850D03*
X1856219Y654417D03*
X1831350Y658417D03*
Y663417D03*
Y668417D03*
X1831300Y652600D03*
X1855676Y800787D03*
X1824170Y886349D03*
X1819541Y921500D03*
X1823937Y890883D03*
X1821152Y907899D03*
X1823350Y1080673D03*
X1858046Y1092779D03*
X1836953Y1103391D03*
X1850363Y1115037D03*
X1847506Y1118794D03*
X1851565Y1118784D03*
X1850280Y1111373D03*
X1816046Y1098532D03*
X1836200Y1130000D03*
X1828850Y1106173D03*
Y1111173D03*
Y1116173D03*
Y1121173D03*
X1824850Y1133173D03*
X1814850D03*
X1819850D03*
X1840585Y1151653D03*
X1836400Y1151900D03*
X1842000Y1344700D03*
X1869500Y179134D03*
X1876938Y181062D03*
X1865669Y201661D03*
X1870669D03*
X1875669D03*
X1880669D03*
X1864232Y508600D03*
X1869500Y633500D03*
X1878900Y637000D03*
X1879669Y652917D03*
X1874669D03*
X1869669D03*
X1864669D03*
X1884800Y890750D03*
X1902441Y888500D03*
X1896943Y894350D03*
X1891676Y917759D03*
X1884500Y912500D03*
X1904000Y933500D03*
Y929000D03*
Y925000D03*
X1906500Y893400D03*
X1909358Y897500D03*
X1904000Y938000D03*
X1873001Y901396D03*
X1904000Y921000D03*
X1872190Y936766D03*
X1867963Y996425D03*
X1887402Y1050193D03*
X1872162Y1055426D03*
X1864617Y1040934D03*
X1888085Y1059938D03*
X1876662Y1055426D03*
X1864833Y1091419D03*
X1870779Y1091763D03*
X1875779D03*
X1880779D03*
X1873500Y1329000D03*
X1911676Y893469D03*
G54D33*
X429724Y116339D03*
Y96654D03*
Y102166D03*
Y110827D03*
X443898Y116339D03*
X458071D03*
X436811Y114764D03*
X450984D03*
X443898Y96654D03*
X458071D03*
X443898Y102166D03*
X458071D03*
X436811Y100591D03*
X450984D03*
X436811Y106103D03*
X450984D03*
X443898Y110827D03*
X458071D03*
X436811Y120276D03*
X450984D03*
X465157Y114764D03*
X472244Y116339D03*
X479331Y114764D03*
X465157Y100591D03*
Y106103D03*
X472244Y96654D03*
Y102166D03*
X479331Y100591D03*
Y106103D03*
X472244Y110827D03*
X465157Y120276D03*
X479331D03*
X514764Y116339D03*
Y110827D03*
Y102166D03*
Y96654D03*
X550197Y114764D03*
X536024D03*
X521850D03*
X543110Y116339D03*
X528937D03*
X543110Y110827D03*
X528937D03*
X550197Y106103D03*
X536024D03*
X521850D03*
X550197Y100591D03*
X536024D03*
X521850D03*
X543110Y102166D03*
X528937D03*
X543110Y96654D03*
X528937D03*
X557283Y116339D03*
Y110827D03*
Y102166D03*
Y96654D03*
X550197Y120276D03*
X536024D03*
X521850D03*
X564370Y114764D03*
Y106103D03*
Y100591D03*
Y120276D03*
X833859Y1598425D03*
Y1603937D03*
Y1612599D03*
X840945Y1602363D03*
X826772D03*
X840945Y1607874D03*
X826772D03*
X840945Y1616536D03*
X826772D03*
X833859Y1618111D03*
Y1626772D03*
Y1632284D03*
Y1640945D03*
Y1646457D03*
X840945Y1622048D03*
X826772D03*
X840945Y1630709D03*
X826772D03*
X840945Y1636221D03*
X826772D03*
X840945Y1644882D03*
X826772D03*
X840945Y1650394D03*
X826772D03*
X876378Y1598425D03*
X862205D03*
X848032D03*
X876378Y1603937D03*
X862205D03*
X848032D03*
X876378Y1612599D03*
X862205D03*
X848032D03*
X890552Y1602363D03*
X869292D03*
X855118D03*
X890552Y1607874D03*
X869292D03*
X855118D03*
X890552Y1612205D03*
Y1616536D03*
X869292D03*
X855118D03*
X876378Y1618111D03*
X862205D03*
X848032D03*
X876378Y1626772D03*
X862205D03*
X848032D03*
X876378Y1632284D03*
X862205D03*
X848032D03*
X876378Y1640945D03*
X862205D03*
X848032D03*
X876378Y1646457D03*
X862205D03*
X848032D03*
X890552Y1622048D03*
X869292D03*
X855118D03*
X890552Y1626378D03*
Y1630709D03*
X869292D03*
X855118D03*
X890552Y1636221D03*
X869292D03*
X855118D03*
X890552Y1640551D03*
Y1644882D03*
X869292D03*
X855118D03*
X890552Y1650394D03*
X869292D03*
X855118D03*
X911811Y1603937D03*
Y1608268D03*
Y1612599D03*
X904725Y1602363D03*
Y1607874D03*
Y1612205D03*
Y1616536D03*
X911811Y1594095D03*
Y1598425D03*
X904725Y1598032D03*
X897638Y1598425D03*
Y1603937D03*
Y1608268D03*
Y1612599D03*
X911811Y1632284D03*
Y1636614D03*
Y1640945D03*
Y1646457D03*
Y1650788D03*
X904725Y1630709D03*
Y1636221D03*
Y1640551D03*
Y1644882D03*
Y1650394D03*
X911811Y1618111D03*
Y1622441D03*
Y1626772D03*
X904725Y1622048D03*
Y1626378D03*
X897638Y1618111D03*
Y1622441D03*
Y1626772D03*
Y1632284D03*
Y1636614D03*
Y1640945D03*
Y1646457D03*
Y1650788D03*
X1095420Y988592D03*
X1100932D03*
X1109593D03*
X1115105D03*
X1123766D03*
X1129278D03*
X1099357Y995678D03*
X1104869D03*
X1113530D03*
X1119042D03*
X1127703D03*
X1133215D03*
X1095420Y1002765D03*
X1100932D03*
X1109593D03*
X1115105D03*
X1123766D03*
X1129278D03*
X1099357Y1009852D03*
X1104869D03*
X1113530D03*
X1119042D03*
X1127703D03*
X1133215D03*
X1095420Y1016938D03*
X1100932D03*
X1109593D03*
X1115105D03*
X1123766D03*
X1129278D03*
X1099357Y1024025D03*
X1104869D03*
X1113530D03*
X1119042D03*
X1127703D03*
X1133215D03*
X1095420Y1031111D03*
X1100932D03*
X1109593D03*
X1115105D03*
X1123766D03*
X1129278D03*
X1099357Y1038198D03*
X1104869D03*
X1113530D03*
X1119042D03*
X1127703D03*
X1133215D03*
X1095420Y1160257D03*
Y1174430D03*
X1100932Y1160257D03*
Y1174430D03*
X1109593Y1160257D03*
Y1174430D03*
X1115105Y1160257D03*
Y1174430D03*
X1123766Y1160257D03*
Y1174430D03*
X1129278Y1160257D03*
Y1174430D03*
X1099357Y1167343D03*
X1104869D03*
X1113530D03*
X1119042D03*
X1127703D03*
X1133215D03*
X1095420Y1188603D03*
Y1202776D03*
Y1216949D03*
X1100932Y1188603D03*
Y1202776D03*
Y1216949D03*
X1109593Y1188603D03*
Y1202776D03*
Y1216949D03*
X1115105Y1188603D03*
Y1202776D03*
Y1216949D03*
X1123766Y1188603D03*
Y1202776D03*
Y1216949D03*
X1129278Y1188603D03*
Y1202776D03*
Y1216949D03*
X1099357Y1181516D03*
Y1195690D03*
Y1209863D03*
Y1224036D03*
X1104869Y1181516D03*
Y1195690D03*
Y1209863D03*
Y1224036D03*
X1113530Y1181516D03*
Y1195690D03*
Y1209863D03*
Y1224036D03*
X1119042Y1181516D03*
Y1195690D03*
Y1209863D03*
Y1224036D03*
X1127703Y1181516D03*
Y1195690D03*
Y1209863D03*
Y1224036D03*
X1133215Y1181516D03*
Y1195690D03*
Y1209863D03*
Y1224036D03*
X1095420Y1231123D03*
Y1245296D03*
Y1259469D03*
Y1273642D03*
X1100932Y1231123D03*
Y1245296D03*
Y1259469D03*
Y1273642D03*
X1109593Y1231123D03*
Y1245296D03*
Y1259469D03*
Y1273642D03*
X1115105Y1231123D03*
Y1245296D03*
Y1259469D03*
Y1273642D03*
X1123766Y1231123D03*
Y1245296D03*
Y1259469D03*
Y1273642D03*
X1129278Y1231123D03*
Y1245296D03*
Y1259469D03*
Y1273642D03*
X1099357Y1238209D03*
Y1252382D03*
Y1266556D03*
X1104869Y1238209D03*
Y1252382D03*
Y1266556D03*
X1113530Y1238209D03*
Y1252382D03*
Y1266556D03*
X1119042Y1238209D03*
Y1252382D03*
Y1266556D03*
X1127703Y1238209D03*
Y1252382D03*
Y1266556D03*
X1133215Y1238209D03*
Y1252382D03*
Y1266556D03*
X1095420Y1287816D03*
Y1301989D03*
Y1316162D03*
X1100932Y1287816D03*
Y1301989D03*
Y1316162D03*
X1109593Y1287816D03*
Y1301989D03*
Y1316162D03*
X1115105Y1287816D03*
Y1301989D03*
Y1316162D03*
X1123766Y1287816D03*
Y1301989D03*
Y1316162D03*
X1129278Y1287816D03*
Y1301989D03*
Y1316162D03*
X1099357Y1280729D03*
Y1294902D03*
Y1309075D03*
Y1323249D03*
X1104869Y1280729D03*
Y1294902D03*
Y1309075D03*
Y1323249D03*
X1113530Y1280729D03*
Y1294902D03*
Y1309075D03*
Y1323249D03*
X1119042Y1280729D03*
Y1294902D03*
Y1309075D03*
Y1323249D03*
X1127703Y1280729D03*
Y1294902D03*
Y1309075D03*
Y1323249D03*
X1133215Y1280729D03*
Y1294902D03*
Y1309075D03*
Y1323249D03*
X1095420Y1330335D03*
Y1344508D03*
Y1358682D03*
Y1372855D03*
X1100932Y1330335D03*
Y1344508D03*
Y1358682D03*
Y1372855D03*
X1109593Y1330335D03*
Y1344508D03*
Y1358682D03*
Y1372855D03*
X1115105Y1330335D03*
Y1344508D03*
Y1358682D03*
Y1372855D03*
X1123766Y1330335D03*
Y1344508D03*
Y1358682D03*
Y1372855D03*
X1129278Y1330335D03*
Y1344508D03*
Y1358682D03*
Y1372855D03*
X1099357Y1337422D03*
Y1351595D03*
Y1365768D03*
X1104869Y1337422D03*
Y1351595D03*
Y1365768D03*
X1113530Y1337422D03*
Y1351595D03*
Y1365768D03*
X1119042Y1337422D03*
Y1351595D03*
Y1365768D03*
X1127703Y1337422D03*
Y1351595D03*
Y1365768D03*
X1133215Y1337422D03*
Y1351595D03*
Y1365768D03*
X1095420Y1387028D03*
Y1401201D03*
X1100932Y1387028D03*
Y1401201D03*
X1109593Y1387028D03*
Y1401201D03*
X1115105Y1387028D03*
Y1401201D03*
X1123766Y1387028D03*
Y1401201D03*
X1129278Y1387028D03*
Y1401201D03*
X1099357Y1379942D03*
Y1394115D03*
Y1408288D03*
X1104869Y1379942D03*
Y1394115D03*
Y1408288D03*
X1113530Y1379942D03*
Y1394115D03*
Y1408288D03*
X1119042Y1379942D03*
Y1394115D03*
Y1408288D03*
X1127703Y1379942D03*
Y1394115D03*
Y1408288D03*
X1133215Y1379942D03*
Y1394115D03*
Y1408288D03*
X1398228Y116339D03*
Y96654D03*
Y102166D03*
Y110827D03*
X1412402Y116339D03*
X1426575D03*
X1405315Y114764D03*
X1419488D03*
X1412402Y96654D03*
X1426575D03*
X1412402Y102166D03*
X1426575D03*
X1405315Y100591D03*
X1419488D03*
X1405315Y106103D03*
X1419488D03*
X1412402Y110827D03*
X1426575D03*
X1405315Y120276D03*
X1419488D03*
X1433661Y114764D03*
X1440748Y116339D03*
X1447835Y114764D03*
X1433661Y100591D03*
Y106103D03*
X1440748Y96654D03*
Y102166D03*
X1447835Y100591D03*
Y106103D03*
X1440748Y110827D03*
X1433661Y120276D03*
X1447835D03*
X1483268Y116339D03*
Y110827D03*
Y102166D03*
Y96654D03*
X1518701Y114764D03*
X1504528D03*
X1490354D03*
X1511614Y116339D03*
X1497441D03*
X1511614Y110827D03*
X1497441D03*
X1518701Y106103D03*
X1504528D03*
X1490354D03*
X1518701Y100591D03*
X1504528D03*
X1490354D03*
X1511614Y102166D03*
X1497441D03*
X1511614Y96654D03*
X1497441D03*
X1518701Y120276D03*
X1504528D03*
X1490354D03*
X1532874Y114764D03*
X1525787Y116339D03*
Y110827D03*
X1532874Y106103D03*
Y100591D03*
X1525787Y102166D03*
Y96654D03*
X1532874Y120276D03*
G54D42*
X988795Y1571058D03*
Y1576658D03*
X1026106Y1545595D03*
Y1539995D03*
X1031706Y1545595D03*
Y1539995D03*
X1020574Y1540059D03*
Y1545659D03*
X1039758Y1559605D03*
X1014974Y1540059D03*
Y1545659D03*
X1039358Y1565405D03*
X1033717Y1563634D03*
X1028223Y1563763D03*
X1022623D03*
X994305Y1566342D03*
X1017023Y1563763D03*
X1011476Y1565175D03*
X1005658Y1565005D03*
X1000058D03*
X1039958Y1553705D03*
Y1548105D03*
Y1542505D03*
X1039358Y1571005D03*
Y1576605D03*
X1005658Y1575905D03*
X1033917Y1574834D03*
X1033717Y1569234D03*
X1000058Y1575905D03*
X1028423Y1574963D03*
X1028223Y1569363D03*
X994460Y1577240D03*
X1022823Y1574963D03*
X1022623Y1569363D03*
X1017223Y1574963D03*
X1017023Y1569363D03*
X994305Y1571942D03*
X1011676Y1576375D03*
X1011476Y1570775D03*
X1005658Y1570605D03*
X1000058D03*
X1078358Y1561105D03*
Y1566705D03*
X1072758Y1561105D03*
Y1566705D03*
X1067158Y1561105D03*
Y1566705D03*
X1061558Y1561105D03*
Y1566705D03*
X1055768Y1566675D03*
X1055418Y1560785D03*
X1055618Y1554885D03*
Y1549285D03*
Y1543685D03*
X1078358Y1572305D03*
X1072758D03*
X1067158D03*
X1061558D03*
X1055768Y1572275D03*
Y1577875D03*
G54D20*
X111024Y302303D03*
Y755059D03*
Y1207815D03*
X235236Y302303D03*
Y755059D03*
Y1207815D03*
X359449Y302303D03*
Y755059D03*
Y1207815D03*
X483661Y302303D03*
Y755059D03*
Y1207815D03*
X607874Y302303D03*
Y755059D03*
Y1207815D03*
X732087Y302303D03*
Y755059D03*
Y1207815D03*
X1098524Y-115157D03*
X1281693Y302303D03*
Y755059D03*
Y1207815D03*
X1405906Y302303D03*
Y755059D03*
Y1207815D03*
X1530118Y302303D03*
Y755059D03*
Y1207815D03*
X1654331Y302303D03*
Y755059D03*
Y1207815D03*
X1778543Y302303D03*
Y755059D03*
Y1207815D03*
X1902756Y302303D03*
Y755059D03*
Y1207815D03*
G54D22*
X119763Y550725D03*
Y546225D03*
Y555225D03*
X124263Y546225D03*
Y550725D03*
Y555225D03*
X141978Y958572D03*
X142006Y978425D03*
X209863Y566625D03*
X199102Y969717D03*
Y974717D03*
X183584Y974789D03*
Y969789D03*
X199392Y985113D03*
X183551Y984789D03*
X212063Y976725D03*
X203063D03*
X207563D03*
X216563D03*
X212063Y981725D03*
X216563D03*
X207563D03*
X203063D03*
X199392Y990113D03*
X183551Y989789D03*
X250650Y556997D03*
Y561997D03*
X265545Y556794D03*
Y561794D03*
X250661Y572936D03*
Y577936D03*
X265590Y572801D03*
Y577801D03*
X225563Y976725D03*
X221063D03*
X225563Y981725D03*
X221063D03*
X269763Y569725D03*
X287763D03*
X292263D03*
X274263D03*
X283263D03*
X278763D03*
X283263Y564725D03*
X287763D03*
X292263D03*
X274263D03*
X269763D03*
X278763D03*
X637592Y593186D03*
X641792D03*
Y597386D03*
X637592D03*
X633392Y593186D03*
Y597386D03*
X629192Y593186D03*
Y597386D03*
X641792Y605786D03*
Y601586D03*
X637592D03*
Y605786D03*
X633392D03*
Y601586D03*
X629192D03*
Y605786D03*
X675913Y586555D03*
Y592955D03*
Y598155D03*
X672082Y582834D03*
X666882D03*
X661682D03*
X656482D03*
X695413Y600755D03*
X699613D03*
X669482Y613934D03*
Y609734D03*
X665282D03*
Y613934D03*
X661082D03*
Y609734D03*
X656882Y613934D03*
Y609734D03*
X675913Y603355D03*
X695413Y604955D03*
X691213Y613355D03*
X695413D03*
X699613D03*
X691213Y609155D03*
X695413D03*
X699613Y604955D03*
Y609155D03*
X703813Y592355D03*
Y596555D03*
Y600755D03*
Y613355D03*
Y609155D03*
Y604955D03*
X1370200Y550500D03*
X1366000D03*
X1378100Y530200D03*
Y534400D03*
X1365500Y538600D03*
X1369700D03*
X1365500Y534400D03*
X1369700D03*
X1373900D03*
X1365500Y530200D03*
X1369700D03*
X1373900D03*
X1375900Y568500D03*
X1366000Y563100D03*
X1370200D03*
Y554700D03*
X1366000D03*
X1370200Y558900D03*
X1366000D03*
X1373700Y582900D03*
X1369500D03*
X1377900Y587100D03*
Y591300D03*
Y595500D03*
X1373700D03*
Y591300D03*
Y587100D03*
X1369500Y595500D03*
Y591300D03*
Y587100D03*
X1377900Y599700D03*
X1373700D03*
X1369500D03*
X1396500Y549500D03*
X1386500Y534400D03*
Y530200D03*
X1382300D03*
Y534400D03*
X1396500Y559900D03*
Y554700D03*
Y565100D03*
X1393000Y568500D03*
X1387300D03*
X1381600D03*
X1382100Y587100D03*
X1386300D03*
X1434441Y590424D03*
X1434581Y586136D03*
X1697261Y1004347D03*
X1692761D03*
Y999847D03*
Y995347D03*
X1697261D03*
Y999847D03*
X1783806Y989468D03*
X1862652Y846508D03*
X1850263Y964540D03*
X1850370Y960239D03*
X1845870D03*
X1845763Y964540D03*
Y956040D03*
X1850263D03*
X1825741Y969210D03*
Y974210D03*
X1840683Y969318D03*
Y974318D03*
X1825744Y986011D03*
X1840578Y985885D03*
X1844863Y983125D03*
X1853863D03*
X1858363D03*
X1849363D03*
X1862863D03*
X1853863Y978125D03*
X1844863D03*
X1849363D03*
X1862863D03*
X1858363D03*
X1825744Y991011D03*
X1840578Y990885D03*
X1873099Y817150D03*
X1878099D03*
X1873099Y821650D03*
X1878099D03*
X1873099Y826150D03*
X1878099D03*
X1877512Y831377D03*
X1882512D03*
X1865202Y831559D03*
X1873012Y831377D03*
X1878099Y812650D03*
X1873099D03*
X1878099Y808150D03*
X1873099D03*
X1878099Y803650D03*
X1873099D03*
X1878373Y846472D03*
X1883373D03*
X1867652Y846508D03*
X1867363Y983125D03*
Y978125D03*
G54D19*
X111024Y153681D03*
Y606437D03*
Y1059193D03*
X235236Y153681D03*
Y606437D03*
Y1059193D03*
X359449Y153681D03*
Y606437D03*
Y1059193D03*
X483661Y153681D03*
Y606437D03*
Y1059193D03*
X607874Y153681D03*
Y606437D03*
Y1059193D03*
X732087Y153681D03*
Y606437D03*
Y1059193D03*
X949902Y-115157D03*
X1281693Y153681D03*
Y606437D03*
Y1059193D03*
X1405906Y153681D03*
Y606437D03*
Y1059193D03*
X1530118Y153681D03*
Y606437D03*
Y1059193D03*
X1654331Y153681D03*
Y606437D03*
Y1059193D03*
X1778543Y153681D03*
Y606437D03*
Y1059193D03*
X1902756Y153681D03*
Y606437D03*
Y1059193D03*
G54D32*
X429724Y68307D03*
X458071D03*
X443898D03*
X429724Y87993D03*
Y82481D03*
Y73819D03*
X458071Y87993D03*
Y82481D03*
X450984Y91930D03*
Y86418D03*
X443898Y87993D03*
Y82481D03*
X436811Y91930D03*
Y86418D03*
X458071Y73819D03*
X450984Y77756D03*
Y72245D03*
X443898Y73819D03*
X436811Y77756D03*
Y72245D03*
X472244Y68307D03*
X479331Y91930D03*
Y86418D03*
X472244Y87993D03*
Y82481D03*
X465157Y91930D03*
Y86418D03*
X479331Y77756D03*
Y72245D03*
X472244Y73819D03*
X465157Y77756D03*
Y72245D03*
X514764Y68307D03*
X543110D03*
X528937D03*
X557283D03*
X514764Y87993D03*
Y82481D03*
Y73819D03*
X550197Y91930D03*
Y86418D03*
X543110Y87993D03*
Y82481D03*
X536024Y91930D03*
Y86418D03*
X528937Y87993D03*
Y82481D03*
X521850Y91930D03*
Y86418D03*
X550197Y77756D03*
Y72245D03*
X543110Y73819D03*
X536024Y77756D03*
Y72245D03*
X528937Y73819D03*
X521850Y77756D03*
Y72245D03*
X557283Y87993D03*
Y82481D03*
Y73819D03*
X564370Y91930D03*
Y86418D03*
Y77756D03*
Y72245D03*
X1398228Y68307D03*
X1426575D03*
X1412402D03*
X1398228Y87993D03*
Y82481D03*
Y73819D03*
X1426575Y87993D03*
Y82481D03*
X1419488Y91930D03*
Y86418D03*
X1412402Y87993D03*
Y82481D03*
X1405315Y91930D03*
Y86418D03*
X1426575Y73819D03*
X1419488Y77756D03*
Y72245D03*
X1412402Y73819D03*
X1405315Y77756D03*
Y72245D03*
X1440748Y68307D03*
X1447835Y91930D03*
Y86418D03*
X1440748Y87993D03*
Y82481D03*
X1433661Y91930D03*
Y86418D03*
X1447835Y77756D03*
Y72245D03*
X1440748Y73819D03*
X1433661Y77756D03*
Y72245D03*
X1483268Y68307D03*
X1511614D03*
X1497441D03*
X1483268Y87993D03*
Y82481D03*
Y73819D03*
X1518701Y91930D03*
Y86418D03*
X1511614Y87993D03*
Y82481D03*
X1504528Y91930D03*
Y86418D03*
X1497441Y87993D03*
Y82481D03*
X1490354Y91930D03*
Y86418D03*
X1518701Y77756D03*
Y72245D03*
X1511614Y73819D03*
X1504528Y77756D03*
Y72245D03*
X1497441Y73819D03*
X1490354Y77756D03*
Y72245D03*
X1525787Y68307D03*
X1532874Y91930D03*
Y86418D03*
X1525787Y87993D03*
Y82481D03*
X1532874Y77756D03*
Y72245D03*
X1525787Y73819D03*
G54D38*
X929331Y16536D03*
X937205Y20473D03*
Y12599D03*
Y67717D03*
X929331Y48032D03*
Y32284D03*
X937205Y44095D03*
Y36221D03*
Y28347D03*
X929331Y103150D03*
Y87402D03*
Y71654D03*
X937205Y114961D03*
Y99213D03*
Y83465D03*
X929331Y166142D03*
Y150394D03*
Y134646D03*
Y118898D03*
X937205Y162205D03*
Y146457D03*
Y130709D03*
X929331Y213386D03*
Y197638D03*
Y181890D03*
X937205Y209449D03*
Y193701D03*
Y177953D03*
X929331Y260630D03*
Y244882D03*
Y229134D03*
X937205Y256693D03*
Y240945D03*
Y225197D03*
X929331Y307874D03*
Y292126D03*
Y276378D03*
X937205Y303937D03*
Y288189D03*
Y272441D03*
X929331Y339371D03*
Y323622D03*
X937205Y335434D03*
Y319685D03*
X929331Y395669D03*
X937205Y407480D03*
Y399606D03*
Y391732D03*
X929331Y450787D03*
X937205Y446850D03*
X929331Y427165D03*
Y419291D03*
Y411417D03*
X937205Y431102D03*
Y423228D03*
Y415354D03*
X929331Y498031D03*
Y482283D03*
Y466535D03*
X937205Y494094D03*
Y478346D03*
Y462598D03*
X929331Y545275D03*
Y529527D03*
Y513779D03*
X937205Y541338D03*
Y525590D03*
Y509842D03*
X929331Y592519D03*
Y576771D03*
Y561023D03*
X937205Y588582D03*
Y572834D03*
Y557086D03*
X929331Y639763D03*
Y624015D03*
Y608267D03*
X937205Y635826D03*
Y620078D03*
Y604330D03*
X929331Y687007D03*
Y671259D03*
Y655511D03*
X937205Y683070D03*
Y667322D03*
Y651574D03*
X929331Y718504D03*
Y702755D03*
X937205Y714567D03*
Y698818D03*
X954921Y16536D03*
X947047Y20473D03*
Y12599D03*
X954921Y63780D03*
X947047Y67717D03*
X954921Y40158D03*
Y32284D03*
X947047Y51969D03*
Y44095D03*
Y36221D03*
Y28347D03*
X954921Y111024D03*
Y95276D03*
Y79528D03*
X947047Y107087D03*
Y91339D03*
Y75591D03*
X954921Y158268D03*
Y142520D03*
Y126772D03*
X947047Y154331D03*
Y138583D03*
Y122835D03*
X954921Y205512D03*
Y189764D03*
Y174016D03*
X947047Y201575D03*
Y185827D03*
Y170079D03*
X954921Y252756D03*
Y237008D03*
Y221260D03*
X947047Y248819D03*
Y233071D03*
Y217323D03*
X954921Y300000D03*
Y284252D03*
Y268504D03*
X947047Y296063D03*
Y280315D03*
Y264567D03*
X954921Y339371D03*
Y331496D03*
Y315748D03*
X947047Y327559D03*
Y311811D03*
X954921Y395669D03*
X947047Y407480D03*
Y399606D03*
Y391732D03*
X954921Y442913D03*
X947047Y454724D03*
X954921Y427165D03*
Y419291D03*
Y411417D03*
X947047Y431102D03*
Y423228D03*
X954921Y490157D03*
Y474409D03*
Y458661D03*
X947047Y501968D03*
Y486220D03*
Y470472D03*
X954921Y553149D03*
Y537401D03*
Y521653D03*
Y505905D03*
X947047Y549212D03*
Y533464D03*
Y517716D03*
X954921Y600393D03*
Y584645D03*
Y568897D03*
X947047Y596456D03*
Y580708D03*
Y564960D03*
X954921Y647637D03*
Y631889D03*
Y616141D03*
X947047Y643700D03*
Y627952D03*
Y612204D03*
X954921Y694881D03*
Y679133D03*
Y663385D03*
X947047Y690944D03*
Y675196D03*
Y659448D03*
X954921Y710629D03*
X947047Y706692D03*
X1123031Y16536D03*
X1097441D03*
X1115157Y20473D03*
Y12599D03*
X1105315Y20473D03*
Y12599D03*
X1123031Y63780D03*
X1115157Y67717D03*
X1105315D03*
X1123031Y40158D03*
Y32284D03*
X1097441Y48032D03*
Y32284D03*
X1115157Y51969D03*
Y44095D03*
Y36221D03*
Y28347D03*
X1105315Y44095D03*
Y36221D03*
Y28347D03*
X1123031Y111024D03*
Y95276D03*
Y79528D03*
X1097441Y103150D03*
Y87402D03*
Y71654D03*
X1115157Y107087D03*
Y91339D03*
Y75591D03*
X1105315Y114961D03*
Y99213D03*
Y83465D03*
X1123031Y158268D03*
Y142520D03*
Y126772D03*
X1097441Y166142D03*
Y150394D03*
Y134646D03*
Y118898D03*
X1115157Y154331D03*
Y138583D03*
Y122835D03*
X1105315Y162205D03*
Y146457D03*
Y130709D03*
X1123031Y205512D03*
Y189764D03*
Y174016D03*
X1097441Y213386D03*
Y197638D03*
Y181890D03*
X1115157Y201575D03*
Y185827D03*
Y170079D03*
X1105315Y209449D03*
Y193701D03*
Y177953D03*
X1123031Y252756D03*
Y237008D03*
Y221260D03*
X1097441Y260630D03*
Y244882D03*
Y229134D03*
X1115157Y248819D03*
Y233071D03*
Y217323D03*
X1105315Y256693D03*
Y240945D03*
Y225197D03*
X1123031Y300000D03*
Y284252D03*
Y268504D03*
X1097441Y307874D03*
Y292126D03*
Y276378D03*
X1115157Y296063D03*
Y280315D03*
Y264567D03*
X1105315Y303937D03*
Y288189D03*
Y272441D03*
X1123031Y339371D03*
Y331496D03*
Y315748D03*
X1097441Y339371D03*
Y323622D03*
X1115157Y327559D03*
Y311811D03*
X1105315Y335434D03*
Y319685D03*
X1123031Y395669D03*
X1097441D03*
X1115157Y407480D03*
Y399606D03*
Y391732D03*
X1105315Y407480D03*
Y399606D03*
Y391732D03*
X1123031Y442913D03*
X1097441Y450787D03*
X1115157Y454724D03*
X1105315Y446850D03*
X1123031Y427165D03*
Y419291D03*
Y411417D03*
X1097441Y427165D03*
Y419291D03*
Y411417D03*
X1115157Y431102D03*
Y423228D03*
X1105315Y431102D03*
Y423228D03*
Y415354D03*
X1123031Y490157D03*
Y474409D03*
Y458661D03*
X1097441Y498031D03*
Y482283D03*
Y466535D03*
X1115157Y501968D03*
Y486220D03*
Y470472D03*
X1105315Y494094D03*
Y478346D03*
Y462598D03*
X1123031Y553149D03*
Y537401D03*
Y521653D03*
Y505905D03*
X1097441Y545275D03*
Y529527D03*
Y513779D03*
X1115157Y549212D03*
Y533464D03*
Y517716D03*
X1105315Y541338D03*
Y525590D03*
Y509842D03*
X1123031Y600393D03*
Y584645D03*
Y568897D03*
X1097441Y592519D03*
Y576771D03*
Y561023D03*
X1115157Y596456D03*
Y580708D03*
Y564960D03*
X1105315Y588582D03*
Y572834D03*
Y557086D03*
X1123031Y647637D03*
Y631889D03*
Y616141D03*
X1097441Y639763D03*
Y624015D03*
Y608267D03*
X1115157Y643700D03*
Y627952D03*
Y612204D03*
X1105315Y635826D03*
Y620078D03*
Y604330D03*
X1123031Y694881D03*
Y679133D03*
Y663385D03*
X1097441Y687007D03*
Y671259D03*
Y655511D03*
X1115157Y690944D03*
Y675196D03*
Y659448D03*
X1105315Y683070D03*
Y667322D03*
Y651574D03*
X1123031Y710629D03*
X1097441Y718504D03*
Y702755D03*
X1115157Y706692D03*
X1105315Y714567D03*
Y698818D03*
G54D43*
X974016Y1642401D03*
X986614D03*
X974016Y1636496D03*
Y1648307D03*
X986614Y1636496D03*
Y1648307D03*
X1030709Y1619764D03*
X1014961D03*
X1002362D03*
Y1613858D03*
X1014961D03*
X1030709D03*
X1002362Y1642401D03*
X1014961D03*
X1030709D03*
X1002362Y1625669D03*
Y1636496D03*
Y1648307D03*
X1014961Y1625669D03*
Y1636496D03*
Y1648307D03*
X1030709Y1625669D03*
Y1636496D03*
Y1648307D03*
X1043307Y1619764D03*
Y1613858D03*
Y1642401D03*
Y1625669D03*
Y1636496D03*
Y1648307D03*
X1101457Y1601181D03*
X1119685D03*
X1108150D03*
X1126378D03*
G54D31*
X313312Y98705D03*
X317812Y98905D03*
X385210Y1166347D03*
X450984Y124507D03*
X436811D03*
X479830D03*
X465157D03*
X550197D03*
X536023D03*
X521850D03*
X564370D03*
X753883Y929689D03*
Y937689D03*
Y945689D03*
X756250Y1140250D03*
X838521Y41568D03*
X838043Y37217D03*
X929331Y63780D03*
Y40158D03*
Y24410D03*
X937205Y51969D03*
X929331Y111024D03*
Y95276D03*
Y79528D03*
X937205Y107087D03*
Y91339D03*
Y75591D03*
X929331Y158268D03*
Y142520D03*
Y126772D03*
X937205Y154331D03*
Y138583D03*
Y122835D03*
X929331Y205512D03*
Y189764D03*
Y174016D03*
X937205Y201575D03*
Y185827D03*
Y170079D03*
X929331Y252756D03*
Y237008D03*
Y221260D03*
X937205Y248819D03*
Y233071D03*
Y217323D03*
X929331Y300000D03*
Y284252D03*
Y268504D03*
X937205Y296063D03*
Y280315D03*
Y264567D03*
X929331Y331496D03*
Y315748D03*
X937205Y327559D03*
Y311811D03*
X929331Y403543D03*
Y442913D03*
X937205Y454724D03*
X929331Y490157D03*
Y474409D03*
Y458661D03*
X937205Y501968D03*
Y486220D03*
Y470472D03*
X929331Y553149D03*
Y537401D03*
Y521653D03*
Y505905D03*
X937205Y549212D03*
Y533464D03*
Y517716D03*
X929331Y600393D03*
Y584645D03*
Y568897D03*
X937205Y596456D03*
Y580708D03*
Y564960D03*
X929331Y647637D03*
Y631889D03*
Y616141D03*
X937205Y643700D03*
Y627952D03*
Y612204D03*
X929331Y694881D03*
Y679133D03*
Y663385D03*
X937205Y690944D03*
Y675196D03*
Y659448D03*
X929331Y710629D03*
X937205Y706692D03*
X942925Y1369010D03*
X928384Y1346435D03*
X932559Y1360137D03*
X928439Y1360167D03*
X954921Y48032D03*
Y24410D03*
Y103150D03*
Y87402D03*
Y71654D03*
X947047Y114961D03*
Y99213D03*
Y83465D03*
X954921Y166142D03*
Y150394D03*
Y134646D03*
Y118898D03*
X947047Y162205D03*
Y146457D03*
Y130709D03*
X954921Y213386D03*
Y197638D03*
Y181890D03*
X947047Y209449D03*
Y193701D03*
Y177953D03*
X954921Y260630D03*
Y244882D03*
Y229134D03*
X947047Y256693D03*
Y240945D03*
Y225197D03*
X954921Y307874D03*
Y292126D03*
Y276378D03*
X947047Y303937D03*
Y288189D03*
Y272441D03*
X954921Y323622D03*
X947047Y335434D03*
Y319685D03*
X954921Y403543D03*
Y450787D03*
X947047Y446850D03*
Y415354D03*
X954921Y498031D03*
Y482283D03*
Y466535D03*
X947047Y494094D03*
Y478346D03*
Y462598D03*
X954921Y545275D03*
Y529527D03*
Y513779D03*
X947047Y541338D03*
Y525590D03*
Y509842D03*
X954921Y592519D03*
Y576771D03*
Y561023D03*
X947047Y588582D03*
Y572834D03*
Y557086D03*
X954921Y639763D03*
Y624015D03*
Y608267D03*
X947047Y635826D03*
Y620078D03*
Y604330D03*
X954921Y687007D03*
Y671259D03*
Y655511D03*
X947047Y683070D03*
Y667322D03*
Y651574D03*
X954921Y718504D03*
Y702755D03*
X947047Y714567D03*
Y698818D03*
X947125Y1369010D03*
X1034916Y-82413D03*
Y-87913D03*
X1011984Y-83066D03*
X1012174Y-88726D03*
X1050100Y392600D03*
Y397600D03*
Y402600D03*
X1044600Y392500D03*
Y397500D03*
Y402500D03*
Y407500D03*
X1050100Y407600D03*
X1044680Y921400D03*
X1097441Y63780D03*
X1123031Y48032D03*
Y24410D03*
X1097441Y40158D03*
Y24410D03*
X1105315Y51969D03*
X1123031Y103150D03*
Y87402D03*
Y71654D03*
X1097441Y111024D03*
Y95276D03*
Y79528D03*
X1115157Y114961D03*
Y99213D03*
Y83465D03*
X1105315Y107087D03*
Y91339D03*
Y75591D03*
X1123031Y166142D03*
Y150394D03*
Y134646D03*
Y118898D03*
X1097441Y158268D03*
Y142520D03*
Y126772D03*
X1115157Y162205D03*
Y146457D03*
Y130709D03*
X1105315Y154331D03*
Y138583D03*
Y122835D03*
X1123031Y213386D03*
Y197638D03*
Y181890D03*
X1097441Y205512D03*
Y189764D03*
Y174016D03*
X1115157Y209449D03*
Y193701D03*
Y177953D03*
X1105315Y201575D03*
Y185827D03*
Y170079D03*
X1123031Y260630D03*
Y244882D03*
Y229134D03*
X1097441Y252756D03*
Y237008D03*
Y221260D03*
X1115157Y256693D03*
Y240945D03*
Y225197D03*
X1105315Y248819D03*
Y233071D03*
Y217323D03*
X1123031Y307874D03*
Y292126D03*
Y276378D03*
X1097441Y300000D03*
Y284252D03*
Y268504D03*
X1115157Y303937D03*
Y288189D03*
Y272441D03*
X1105315Y296063D03*
Y280315D03*
Y264567D03*
X1123031Y323622D03*
X1097441Y331496D03*
Y315748D03*
X1115157Y335434D03*
Y319685D03*
X1105315Y327559D03*
Y311811D03*
X1123031Y403543D03*
X1097441D03*
X1123031Y450787D03*
X1097441Y442913D03*
X1115157Y446850D03*
X1105315Y454724D03*
X1115157Y415354D03*
X1123031Y498031D03*
Y482283D03*
Y466535D03*
X1097441Y490157D03*
Y474409D03*
Y458661D03*
X1115157Y494094D03*
Y478346D03*
Y462598D03*
X1105315Y501968D03*
Y486220D03*
Y470472D03*
X1123031Y545275D03*
Y529527D03*
Y513779D03*
X1097441Y553149D03*
Y537401D03*
Y521653D03*
Y505905D03*
X1115157Y541338D03*
Y525590D03*
Y509842D03*
X1105315Y549212D03*
Y533464D03*
Y517716D03*
X1123031Y592519D03*
Y576771D03*
Y561023D03*
X1097441Y600393D03*
Y584645D03*
Y568897D03*
X1115157Y588582D03*
Y572834D03*
Y557086D03*
X1105315Y596456D03*
Y580708D03*
Y564960D03*
X1123031Y639763D03*
Y624015D03*
Y608267D03*
X1097441Y647637D03*
Y631889D03*
Y616141D03*
X1115157Y635826D03*
Y620078D03*
Y604330D03*
X1105315Y643700D03*
Y627952D03*
Y612204D03*
X1123031Y687007D03*
Y671259D03*
Y655511D03*
X1097441Y694881D03*
Y679133D03*
Y663385D03*
X1115157Y683070D03*
Y667322D03*
Y651574D03*
X1105315Y690944D03*
Y675196D03*
Y659448D03*
X1123031Y718504D03*
Y702755D03*
X1097441Y710629D03*
X1115157Y714567D03*
Y698818D03*
X1105315Y706692D03*
X1119159Y878130D03*
Y873130D03*
Y868130D03*
X1116159Y870630D03*
Y875630D03*
X1259800Y631998D03*
Y619498D03*
Y1072254D03*
Y1084754D03*
X1384013Y631998D03*
Y619498D03*
Y1072254D03*
Y1084754D03*
X1447834Y124507D03*
X1504527D03*
X1490354D03*
X1518701D03*
X1508225Y631998D03*
Y619498D03*
Y1072254D03*
Y1084754D03*
X1532874Y124507D03*
X1632438Y179242D03*
Y166742D03*
Y631998D03*
Y619498D03*
Y1072254D03*
Y1084754D03*
X1756650Y179242D03*
Y166742D03*
X1731650Y631998D03*
Y619498D03*
X1756650Y1072254D03*
Y1084754D03*
X1880863Y179242D03*
Y166742D03*
Y631998D03*
Y619498D03*
Y1072254D03*
X1884835Y1067400D03*
X1880863Y1084754D03*
G54D11*
X24508Y5500D03*
X20000Y60000D03*
X5500Y61492D03*
Y56492D03*
Y51492D03*
Y46492D03*
Y41492D03*
Y66492D03*
X20000Y80000D03*
Y100000D03*
X5500Y81492D03*
Y76492D03*
Y96492D03*
Y91492D03*
Y86492D03*
Y71492D03*
Y101492D03*
Y111492D03*
Y116492D03*
Y106492D03*
X20000Y120000D03*
Y140000D03*
Y160000D03*
X5500Y126492D03*
Y121492D03*
Y141492D03*
Y151492D03*
Y161492D03*
Y156492D03*
Y146492D03*
Y131492D03*
Y136492D03*
X20000Y180000D03*
Y200000D03*
X5500Y181492D03*
Y191492D03*
Y201492D03*
Y211492D03*
Y171492D03*
Y206492D03*
Y196492D03*
Y176492D03*
Y166492D03*
Y186492D03*
X20000Y220000D03*
Y240000D03*
Y260000D03*
X5500Y231492D03*
Y241492D03*
Y251492D03*
Y261492D03*
Y221492D03*
Y256492D03*
Y246492D03*
Y226492D03*
Y216492D03*
Y236492D03*
X20000Y280000D03*
Y300000D03*
X5500Y281492D03*
Y291492D03*
Y301492D03*
Y271492D03*
Y306492D03*
Y296492D03*
Y286492D03*
Y276492D03*
Y266492D03*
X20000Y320000D03*
Y340000D03*
X5500Y331492D03*
Y341492D03*
Y351492D03*
Y311492D03*
Y321492D03*
Y356492D03*
Y346492D03*
Y336492D03*
Y326492D03*
Y316492D03*
X20000Y360000D03*
Y380000D03*
Y400000D03*
X5500Y381492D03*
Y391492D03*
Y401492D03*
Y361492D03*
Y371492D03*
Y406492D03*
Y396492D03*
Y386492D03*
Y376492D03*
Y366492D03*
X20000Y420000D03*
Y440000D03*
X5500Y451492D03*
Y441492D03*
Y431492D03*
Y421492D03*
Y411492D03*
Y416492D03*
Y436492D03*
Y446492D03*
Y426492D03*
Y501492D03*
Y456492D03*
Y496492D03*
Y531492D03*
Y551492D03*
Y541492D03*
Y521492D03*
Y511492D03*
Y536492D03*
Y546492D03*
Y506492D03*
Y516492D03*
Y526492D03*
Y581492D03*
Y591492D03*
Y571492D03*
Y561492D03*
Y586492D03*
Y596492D03*
Y556492D03*
Y566492D03*
Y576492D03*
Y631492D03*
Y641492D03*
Y621492D03*
Y611492D03*
Y601492D03*
Y636492D03*
Y646492D03*
Y606492D03*
Y616492D03*
Y626492D03*
Y681492D03*
Y691492D03*
Y671492D03*
Y661492D03*
Y651492D03*
Y686492D03*
Y696492D03*
Y656492D03*
Y666492D03*
Y676492D03*
Y731492D03*
Y741492D03*
Y721492D03*
Y711492D03*
Y701492D03*
Y736492D03*
Y706492D03*
Y716492D03*
Y726492D03*
Y781492D03*
Y791492D03*
Y771492D03*
Y761492D03*
Y751492D03*
Y786492D03*
Y746492D03*
Y756492D03*
Y766492D03*
Y776492D03*
Y831492D03*
Y841492D03*
Y821492D03*
Y811492D03*
Y801492D03*
Y836492D03*
Y796492D03*
Y806492D03*
Y816492D03*
Y826492D03*
Y881492D03*
Y871492D03*
Y861492D03*
Y851492D03*
Y886492D03*
Y846492D03*
Y856492D03*
Y866492D03*
Y876492D03*
X15000Y930000D03*
Y920000D03*
X25000Y930000D03*
Y920000D03*
X5500Y931492D03*
Y921492D03*
Y911492D03*
Y901492D03*
Y891492D03*
Y936492D03*
Y896492D03*
Y906492D03*
Y916492D03*
Y926492D03*
X15000Y980000D03*
Y970000D03*
Y960000D03*
Y950000D03*
Y940000D03*
X25000D03*
Y950000D03*
Y960000D03*
Y970000D03*
Y980000D03*
X5500Y976492D03*
Y981492D03*
Y986492D03*
Y966492D03*
Y956492D03*
Y961492D03*
Y971492D03*
Y951492D03*
Y941492D03*
Y946492D03*
X15000Y1030000D03*
Y1020000D03*
Y1010000D03*
Y1000000D03*
Y990000D03*
X25000D03*
Y1000000D03*
Y1010000D03*
Y1020000D03*
X5500Y991492D03*
Y996492D03*
Y1001492D03*
Y1006492D03*
Y1026492D03*
Y1016492D03*
Y1011492D03*
Y1021492D03*
Y1031492D03*
X25000Y1040000D03*
Y1080000D03*
Y1070000D03*
Y1060000D03*
Y1050000D03*
X5500Y1036492D03*
Y1066492D03*
Y1056492D03*
Y1046492D03*
Y1041492D03*
Y1051492D03*
Y1061492D03*
Y1071492D03*
Y1081492D03*
Y1076492D03*
X25000Y1090000D03*
X5500Y1121492D03*
Y1131492D03*
Y1111492D03*
Y1101492D03*
Y1091492D03*
Y1086492D03*
Y1096492D03*
Y1106492D03*
Y1116492D03*
Y1126492D03*
Y1171492D03*
Y1161492D03*
Y1151492D03*
Y1141492D03*
Y1136492D03*
Y1146492D03*
Y1156492D03*
Y1166492D03*
Y1176492D03*
Y1221492D03*
Y1211492D03*
Y1201492D03*
Y1191492D03*
Y1181492D03*
Y1186492D03*
Y1196492D03*
Y1206492D03*
Y1216492D03*
Y1226492D03*
X17500Y1270000D03*
Y1260000D03*
Y1250000D03*
Y1240000D03*
X5500Y1271492D03*
Y1261492D03*
Y1251492D03*
Y1241492D03*
Y1231492D03*
Y1236492D03*
Y1246492D03*
Y1256492D03*
Y1266492D03*
Y1276492D03*
X17500Y1290000D03*
Y1280000D03*
Y1300000D03*
Y1310000D03*
X5500Y1321492D03*
Y1311492D03*
Y1301492D03*
Y1291492D03*
Y1281492D03*
Y1286492D03*
Y1296492D03*
Y1306492D03*
Y1316492D03*
X17500Y1320000D03*
Y1360000D03*
Y1350000D03*
Y1330000D03*
Y1340000D03*
X8983Y1368303D03*
X13983D03*
X18983D03*
X23983D03*
X5500Y1361492D03*
Y1351492D03*
Y1341492D03*
Y1331492D03*
Y1336492D03*
Y1346492D03*
Y1356492D03*
Y1326492D03*
X60000Y20000D03*
X29508Y5500D03*
X39508D03*
X34508D03*
X44508D03*
X64508D03*
X69508D03*
X54508D03*
X49508D03*
X59508D03*
X60000Y40000D03*
X40000D03*
X60000Y60000D03*
X40000D03*
Y80000D03*
X60000D03*
Y100000D03*
X40000D03*
X60000Y120000D03*
X40000D03*
Y140000D03*
X60000D03*
Y160000D03*
X40000D03*
X38500Y202000D03*
X64487Y212761D03*
X56000Y237000D03*
X73437Y247161D03*
X49437Y254661D03*
X73437Y234661D03*
X62000Y276500D03*
X40000Y280000D03*
Y300000D03*
X60000D03*
Y320000D03*
X40000D03*
X60000Y340000D03*
X40000D03*
Y360000D03*
X35000Y446500D03*
X50500Y545500D03*
X58346Y516473D03*
X54088Y512336D03*
X39853Y512373D03*
X44111Y516510D03*
X40000Y560000D03*
Y580000D03*
Y600000D03*
Y620000D03*
X39000Y646000D03*
X30697Y679553D03*
X73437Y687417D03*
X64487Y665417D03*
X31043Y689115D03*
X30676Y663764D03*
X49500Y729000D03*
X49437Y707417D03*
X73437Y699917D03*
X31064Y704904D03*
X69500Y777000D03*
X51000Y755500D03*
X38500Y800500D03*
X39000Y834500D03*
X49000Y811000D03*
X51000Y846000D03*
X40000Y930000D03*
Y920000D03*
Y970000D03*
Y960000D03*
Y950000D03*
Y940000D03*
X50000Y1030000D03*
X70000Y1020000D03*
X40000Y1000000D03*
Y990000D03*
X50000Y1060000D03*
X64487Y1118173D03*
X30256Y1116731D03*
X30670Y1132472D03*
X30644Y1157871D03*
X49437Y1160173D03*
X73437Y1140173D03*
Y1152673D03*
X30623Y1142082D03*
X52000Y1186000D03*
X71500Y1205000D03*
X45800Y1306100D03*
X37500Y1360000D03*
X27500D03*
X28983Y1368303D03*
X33983D03*
X38983D03*
X43983D03*
X48983D03*
X53983D03*
X58983D03*
X63983D03*
X68983D03*
X114508Y5500D03*
X119508D03*
X104508D03*
X94508D03*
X84508D03*
X74508D03*
X79508D03*
X89508D03*
X99508D03*
X109508D03*
X80000Y80000D03*
X100000D03*
X120000D03*
Y100000D03*
X100000D03*
X80000D03*
X120000Y120000D03*
X100000D03*
X80000D03*
X86500Y157500D03*
X80000Y140000D03*
X118437Y141870D03*
X78500Y169500D03*
X111437Y195492D03*
X106937Y198543D03*
Y207992D03*
X111437Y165492D03*
Y180492D03*
X74937Y187461D03*
X92287Y194661D03*
X86637Y194861D03*
X82000Y219000D03*
X111437Y245492D03*
Y235492D03*
X106937Y217441D03*
X111437Y265492D03*
Y275492D03*
X89237Y276861D03*
X95437Y300161D03*
X96000Y336500D03*
X80000Y320000D03*
Y340000D03*
X118437Y314114D03*
X89000Y403500D03*
X100000Y420000D03*
X120000Y440000D03*
X100000D03*
Y460000D03*
X120000D03*
Y480000D03*
X100000D03*
X120000Y500000D03*
X100000D03*
X104500Y515500D03*
X120500Y524000D03*
X86500Y522000D03*
X100000Y541500D03*
X87000Y541000D03*
X89000Y557500D03*
X108500Y572000D03*
X88000Y577500D03*
X118753Y594626D03*
X88000Y602500D03*
X111437Y648248D03*
Y633248D03*
Y618248D03*
X92287Y647417D03*
X86637Y647617D03*
X74937Y640217D03*
X81500Y672000D03*
X106937Y670197D03*
X111437Y688248D03*
X106937Y660748D03*
Y651299D03*
X111437Y728248D03*
Y718248D03*
Y698248D03*
X89237Y729617D03*
X75500Y757500D03*
X94000Y789000D03*
X118437Y766870D03*
X95437Y752917D03*
X89500Y802500D03*
X90000Y858000D03*
X100000Y880000D03*
Y900000D03*
X120000D03*
Y920000D03*
X100000D03*
X120000Y940000D03*
X83100Y984800D03*
X78600D03*
X83100Y980300D03*
X78600D03*
X100000Y940000D03*
X120000Y1025000D03*
X85000Y1020000D03*
X78600Y989300D03*
X83100D03*
X74000Y1074000D03*
X85000Y1060000D03*
X111437Y1071004D03*
X118437Y1047382D03*
X81000Y1124500D03*
X106937Y1122953D03*
Y1113504D03*
Y1104055D03*
X111437Y1101004D03*
Y1086004D03*
X92287Y1100173D03*
X86637Y1100373D03*
X74937Y1092973D03*
X111437Y1171004D03*
Y1151004D03*
Y1141004D03*
X118437Y1219626D03*
X111437Y1181004D03*
X89237Y1182373D03*
X95437Y1205673D03*
X98500Y1241000D03*
X90000Y1252500D03*
X86000Y1282000D03*
X93000Y1319000D03*
X73983Y1368303D03*
X78983D03*
X83983D03*
X88983D03*
X93983D03*
X98983D03*
X107374Y1369303D03*
X112374D03*
X117374D03*
X160000Y20000D03*
X134508Y5500D03*
X124508D03*
X129508D03*
X169508D03*
X159508D03*
X149508D03*
X139508D03*
X154508D03*
X164508D03*
X144508D03*
X160000Y60000D03*
Y40000D03*
X140000D03*
Y60000D03*
X160000Y100000D03*
Y80000D03*
X140000D03*
Y100000D03*
X160000Y140000D03*
X140000D03*
X160000Y120000D03*
X140000D03*
X156500Y170500D03*
X130500Y211500D03*
X160500Y190000D03*
X160000Y180000D03*
X129000Y259000D03*
X142687Y237161D03*
X128000Y288500D03*
X160000Y280000D03*
X140000Y300000D03*
X160000D03*
X140000Y320000D03*
X160000D03*
X140000Y440000D03*
Y460000D03*
Y480000D03*
Y500000D03*
X142500Y515500D03*
X150000Y526500D03*
X164107Y512331D03*
X168365Y516368D03*
X135000Y588000D03*
X167000Y613000D03*
X147500Y605500D03*
X142687Y689917D03*
X135200Y738400D03*
X153705Y744831D03*
X153714Y720741D03*
X153757Y710653D03*
X140372Y732370D03*
X160000Y880000D03*
Y900000D03*
X140000Y920000D03*
X160000D03*
Y940000D03*
X140000D03*
X156000Y1032000D03*
X134000Y1064000D03*
X153000Y1105000D03*
X132000Y1117000D03*
X142687Y1142673D03*
X154363Y1161725D03*
X153716Y1174793D03*
X170000Y1190500D03*
X153824Y1197248D03*
X153932Y1182940D03*
X122374Y1369303D03*
X127374D03*
X132374D03*
X137374D03*
X142374D03*
X147374D03*
X152374D03*
X157374D03*
X162374D03*
X167374D03*
X200000Y20000D03*
X180000D03*
X209508Y5500D03*
X199508D03*
X189508D03*
X179508D03*
X204508D03*
X214508D03*
X174508D03*
X184508D03*
X194508D03*
X200000Y40000D03*
X180000D03*
X200000Y60000D03*
X180000D03*
Y80000D03*
X200000D03*
Y100000D03*
X180000D03*
Y120000D03*
X200000D03*
Y140000D03*
X180000D03*
X216500Y194756D03*
X210849Y194861D03*
X199149Y187461D03*
X188699Y212561D03*
X206000Y219000D03*
X180500Y237000D03*
X197649Y234661D03*
X173649Y254661D03*
X197649Y247161D03*
X180000Y300000D03*
X213449Y276861D03*
X180000Y320000D03*
Y340000D03*
X200000D03*
X178342Y512294D03*
X182600Y516331D03*
X210000Y644000D03*
X216499Y636917D03*
X199149Y631217D03*
X210849Y638617D03*
X206000Y672000D03*
X197649Y687417D03*
X213449Y729617D03*
X173649Y707417D03*
X197649Y699917D03*
X180000Y860000D03*
Y880000D03*
Y920000D03*
Y900000D03*
X215563Y1001225D03*
X203563D03*
X207563D03*
X211563D03*
X211000Y1065000D03*
X203500Y1124500D03*
X216499Y1100173D03*
X210849Y1100373D03*
X199149Y1092973D03*
X188399Y1113873D03*
X175000Y1143000D03*
X173649Y1160173D03*
X193423Y1140945D03*
X197649Y1152673D03*
X213449Y1182373D03*
X181000Y1261000D03*
X190000Y1320000D03*
X200000D03*
X210000D03*
Y1300000D03*
Y1310000D03*
X200000D03*
X190000D03*
X172374Y1369303D03*
X177374D03*
X182374D03*
X187374D03*
X192374D03*
X197374D03*
X202374D03*
X207374D03*
X212374D03*
X217374D03*
X260000Y20000D03*
X220000D03*
X240000D03*
X259508Y5500D03*
X249508D03*
X239508D03*
X229508D03*
X219508D03*
X224508D03*
X234508D03*
X244508D03*
X254508D03*
X264508D03*
X260000Y60000D03*
Y40000D03*
X240000D03*
X220000D03*
Y60000D03*
X240000D03*
X260000Y100000D03*
Y80000D03*
X240000D03*
X220000D03*
Y100000D03*
X240000D03*
X260000Y140000D03*
Y120000D03*
X240000D03*
X220000D03*
X242649Y141870D03*
X262000Y209000D03*
X235649Y195492D03*
X231991Y198543D03*
X231149Y207992D03*
X235649Y165492D03*
Y180492D03*
X253000Y260000D03*
X266899Y237161D03*
X235649Y245492D03*
Y235492D03*
X231149Y217441D03*
X255000Y280000D03*
X235649Y265492D03*
Y275492D03*
X219649Y300161D03*
X242649Y314114D03*
X220000Y360000D03*
X240000Y380000D03*
X220000D03*
Y400000D03*
X240000D03*
Y420000D03*
X220000D03*
Y440000D03*
X240000D03*
Y460000D03*
X220000D03*
Y480000D03*
X240000D03*
Y500000D03*
X220000D03*
Y520000D03*
X243051Y594626D03*
X235649Y648248D03*
Y633248D03*
Y618248D03*
X255500Y664500D03*
X231149Y670197D03*
X235649Y688248D03*
X231149Y660748D03*
Y651299D03*
X266899Y689917D03*
X235649Y728248D03*
Y718248D03*
Y698248D03*
X264739Y732114D03*
X242649Y766870D03*
X219649Y752917D03*
X248500Y788500D03*
X225000Y840000D03*
X245000D03*
X265000Y795000D03*
X225000Y815000D03*
Y880000D03*
X245000D03*
X225000Y860000D03*
X245000D03*
X225000Y900000D03*
X245000D03*
Y940000D03*
X263000Y1023000D03*
X219563Y1001225D03*
X223563D03*
X263000Y1047000D03*
X235649Y1071004D03*
X242649Y1047382D03*
X231149Y1122953D03*
Y1113504D03*
Y1104055D03*
X235649Y1101004D03*
Y1086004D03*
Y1171004D03*
Y1151004D03*
X235300Y1142700D03*
X266899Y1141173D03*
X255000Y1207500D03*
X242649Y1219626D03*
X235649Y1181004D03*
X219649Y1205673D03*
X257000Y1253000D03*
X220000Y1270000D03*
Y1320000D03*
X230000D03*
X240000D03*
X250000D03*
X260000D03*
X220000Y1280000D03*
X230000D03*
X250000Y1290000D03*
X240000D03*
X230000D03*
X220000D03*
Y1300000D03*
X230000D03*
X240000D03*
X250000D03*
X260000D03*
Y1310000D03*
X250000D03*
X240000D03*
X230000D03*
X220000D03*
X222374Y1369303D03*
X227374D03*
X232374D03*
X237374D03*
X242374D03*
X247374D03*
X252374D03*
X257374D03*
X262374D03*
X300000Y20000D03*
X280000D03*
X309508Y5500D03*
X299508D03*
X289508D03*
X279508D03*
X269508D03*
X304508D03*
X314508D03*
X274508D03*
X284508D03*
X294508D03*
X300000Y40000D03*
X280000Y60000D03*
Y40000D03*
Y100000D03*
Y80000D03*
X312355Y72855D03*
X280000Y140000D03*
Y120000D03*
X270000Y179500D03*
X285500Y189500D03*
X283000Y181000D03*
X314329Y212420D03*
X304500Y237000D03*
X297862Y254661D03*
X300000Y300000D03*
Y320000D03*
Y340000D03*
X295000Y400000D03*
Y440000D03*
Y460000D03*
X302513Y512294D03*
X306771Y516331D03*
X292536Y516368D03*
X288278Y512331D03*
X282263Y589225D03*
X270263D03*
X274263D03*
X286263D03*
X290263D03*
X278263D03*
X277000Y618500D03*
X275000Y647000D03*
X294500Y607500D03*
X284000D03*
X312912Y665417D03*
X277972Y744575D03*
X297862Y707417D03*
X277981Y720485D03*
X278024Y710397D03*
X286000Y810500D03*
X305200Y1068400D03*
X295200Y1078400D03*
Y1058400D03*
X281000Y1105000D03*
X312912Y1118273D03*
X304500Y1142500D03*
X302452Y1165162D03*
X278577Y1161725D03*
X277930Y1175001D03*
X306000Y1182500D03*
X278076Y1197355D03*
X278146Y1182940D03*
X301000Y1231000D03*
X267374Y1369303D03*
X272374D03*
X277374D03*
X282374D03*
X287374D03*
X292374D03*
X297374D03*
X302374D03*
X307374D03*
X312374D03*
X360000Y20000D03*
X340000D03*
X320000D03*
X359508Y5500D03*
X349508D03*
X339508D03*
X329508D03*
X319508D03*
X324508D03*
X334508D03*
X344508D03*
X354508D03*
X360000Y40000D03*
X340000D03*
X320000D03*
X355200Y58400D03*
X346245Y58745D03*
X353001Y81799D03*
X351000Y70700D03*
X328000Y150500D03*
X333021Y129679D03*
X359862Y165492D03*
Y180492D03*
Y195492D03*
X355362Y198543D03*
Y207992D03*
X323362Y187461D03*
X340712Y194661D03*
X335062Y194861D03*
X333500Y219000D03*
X359862Y245492D03*
Y235492D03*
X355362Y217441D03*
X321862Y234661D03*
Y247161D03*
X359862Y265492D03*
Y275492D03*
X337662Y276861D03*
X343862Y300161D03*
X352000Y331000D03*
X320000Y340000D03*
X350000Y440000D03*
X330000D03*
X350000Y500000D03*
Y480000D03*
Y460000D03*
X330000D03*
Y540000D03*
X350000D03*
Y520000D03*
X333000Y560000D03*
Y580000D03*
X350000Y560000D03*
X333000Y604000D03*
X359862Y648248D03*
Y633248D03*
Y618248D03*
X340712Y647517D03*
X335062Y647617D03*
X323362Y640217D03*
X330000Y672000D03*
X355362Y670197D03*
X359862Y688248D03*
X355362Y660748D03*
Y651299D03*
X321862Y687417D03*
X359862Y728248D03*
Y718248D03*
Y698248D03*
X337662Y729617D03*
X321862Y699917D03*
X355000Y780500D03*
X320000Y750000D03*
X330000Y770000D03*
X347000Y788500D03*
X343862Y752917D03*
X361500Y901500D03*
X330000Y900000D03*
X360000Y960000D03*
Y940000D03*
X330000Y960000D03*
X322000Y988500D03*
X362000Y1017000D03*
X328000Y1061000D03*
X359862Y1071004D03*
X355362Y1122953D03*
Y1113504D03*
Y1104055D03*
X359862Y1101004D03*
Y1086004D03*
X340812Y1100273D03*
X335062Y1100373D03*
X323362Y1092973D03*
X358518Y1171114D03*
X359862Y1151004D03*
Y1141004D03*
X321862Y1140173D03*
Y1152673D03*
X327500Y1197000D03*
X359862Y1181004D03*
X337662Y1182373D03*
X343862Y1205673D03*
X353000Y1231000D03*
X330000Y1302000D03*
X333983Y1368303D03*
X338983D03*
X343983D03*
X348983D03*
X353983D03*
X358983D03*
X363983D03*
X317374Y1369303D03*
X322374D03*
X327374D03*
X380000Y20000D03*
X395075Y18639D03*
Y13639D03*
X389508Y5500D03*
X379508D03*
X369508D03*
X364508D03*
X374508D03*
X384508D03*
X394508D03*
X380000Y60000D03*
Y40000D03*
X395075Y43639D03*
Y38639D03*
Y33639D03*
Y28639D03*
Y23639D03*
X399000Y62000D03*
X396000Y55500D03*
X396075Y50248D03*
X401000Y89000D03*
X400000Y80000D03*
X365162Y88731D03*
Y77731D03*
X388500Y153500D03*
X395500Y160500D03*
X366862Y141870D03*
X386000Y209000D03*
X390312Y237161D03*
X389000Y289000D03*
X385500Y313000D03*
X366862Y314114D03*
X390000Y500000D03*
X370000D03*
X390000Y540000D03*
Y520000D03*
X370000D03*
Y540000D03*
X389000Y594500D03*
X390000Y560000D03*
X370000D03*
X366862Y594626D03*
X395000Y631000D03*
X388000Y607000D03*
X410000Y692500D03*
X379000Y664000D03*
X391112Y689917D03*
X402129Y744503D03*
X388796Y732042D03*
X402138Y720413D03*
X402181Y710325D03*
X402500Y780500D03*
X366862Y766870D03*
X397000Y911000D03*
X380000Y960000D03*
Y940000D03*
X393500Y988500D03*
Y1017000D03*
X390000Y1055000D03*
X366862Y1047382D03*
X391112Y1142673D03*
X399474Y1166787D03*
X366862Y1219626D03*
X406037Y1192706D03*
X402403Y1188312D03*
X368983Y1368303D03*
X373983D03*
X378983D03*
X383983D03*
X388983D03*
X393983D03*
X398983D03*
X403983D03*
X408983D03*
X437124Y212661D03*
X447574Y187461D03*
X446074Y247161D03*
X422300Y254661D03*
X446074Y234661D03*
X430000Y545500D03*
X460000Y540000D03*
X426663Y512257D03*
X430921Y516294D03*
X416686Y516331D03*
X412428Y512294D03*
X460000Y600000D03*
X445000D03*
X440000Y560000D03*
X460000D03*
X440000Y613000D03*
X459274Y647617D03*
X447574Y640217D03*
X417000Y652500D03*
X454500Y672000D03*
X446074Y687417D03*
X437224Y665417D03*
X452500Y744500D03*
X437500Y744000D03*
X422074Y707417D03*
X446074Y699917D03*
X455000Y780000D03*
X445000D03*
X440000Y760000D03*
X445000Y798000D03*
X428000Y988500D03*
X424000Y1105000D03*
X418500Y1176800D03*
X437104Y1160696D03*
X450500Y1208500D03*
X424000Y1206000D03*
X454500Y1248500D03*
X460000Y1320000D03*
X440000D03*
X460000Y1300000D03*
X413983Y1368303D03*
X418983D03*
X423983D03*
X428983D03*
X433983D03*
X438983D03*
X443983D03*
X448983D03*
X453983D03*
X458983D03*
X476319Y144481D03*
X506750Y165324D03*
X480159Y201245D03*
X500184Y200328D03*
X497785Y178034D03*
X478306Y195593D03*
X461122Y194861D03*
X484074Y245492D03*
X478651Y220734D03*
X484074Y235492D03*
Y275492D03*
X481174Y265492D03*
X461874Y276861D03*
X468074Y300161D03*
X491074Y314114D03*
X470000Y400000D03*
Y380000D03*
Y430000D03*
X465000Y491000D03*
X506746Y512331D03*
X499000Y553000D03*
X491074Y594626D03*
X484074Y648248D03*
Y633248D03*
Y618248D03*
X464924Y647417D03*
X479574Y670197D03*
X484074Y688248D03*
X479574Y660748D03*
Y651299D03*
X484074Y728248D03*
Y718248D03*
Y698248D03*
X461874Y729617D03*
X461500Y769500D03*
X491074Y766870D03*
X468074Y752917D03*
X500000Y960000D03*
Y940000D03*
X480000Y960000D03*
Y940000D03*
X504000Y988500D03*
X462000D03*
X468000Y1047000D03*
X484074Y1071004D03*
X491074Y1047382D03*
X479574Y1113504D03*
Y1104055D03*
X484074Y1101004D03*
Y1086004D03*
X504724Y1118073D03*
X484074Y1171004D03*
Y1151004D03*
Y1141004D03*
X506700Y1141973D03*
X502500Y1211500D03*
X476373Y1219498D03*
X484074Y1181004D03*
X461874Y1182373D03*
X468074Y1205673D03*
X480000Y1320000D03*
X500000Y1300000D03*
X480000D03*
Y1280000D03*
X463983Y1368303D03*
X468983D03*
X473983D03*
X478983D03*
X483983D03*
X488983D03*
X493983D03*
X498983D03*
X503983D03*
X508983D03*
X519868Y242334D03*
X515500Y301000D03*
X550987Y262810D03*
X548500Y343000D03*
X515000Y322500D03*
X547500Y440000D03*
X520981Y512294D03*
X525239Y516331D03*
X511004Y516368D03*
X540000Y600000D03*
X520000D03*
X528000Y611000D03*
X532000Y623000D03*
X515324Y689917D03*
X526225Y744756D03*
X546287Y707417D03*
X512892Y732295D03*
X526277Y710578D03*
X526234Y720666D03*
X509000Y772000D03*
X555500Y852000D03*
X551500Y888000D03*
X523500Y883500D03*
X525000Y937000D03*
X525500Y967000D03*
X523000Y1045000D03*
X528500Y1073500D03*
X546287Y1160173D03*
X535320Y1152771D03*
X534874Y1139774D03*
X526523Y1177122D03*
X526501Y1166546D03*
X526388Y1197747D03*
X526367Y1183111D03*
X539000Y1309000D03*
X517374Y1369303D03*
X522374D03*
X527374D03*
X532374D03*
X537374D03*
X542374D03*
X547374D03*
X552374D03*
X557374D03*
X597051Y7699D03*
Y12699D03*
Y17699D03*
X604146Y5500D03*
X597051Y22699D03*
Y27699D03*
Y32699D03*
Y37699D03*
Y42699D03*
X589000Y64000D03*
X594000Y61500D03*
X596000Y56500D03*
X596051Y51090D03*
X603787Y207992D03*
X604517Y196263D03*
X603697Y182091D03*
X586719Y196888D03*
X568687Y187660D03*
X583487Y194861D03*
X588188Y216520D03*
X570287Y234661D03*
X563000Y217600D03*
X569009Y247887D03*
X592287Y300161D03*
X582758Y276861D03*
X590000Y342000D03*
X560000Y438500D03*
X594500Y462000D03*
X592000Y595000D03*
X580000Y600000D03*
X560000D03*
X586000Y611000D03*
X589137Y647417D03*
X583487Y647617D03*
X571787Y640217D03*
X579000Y672000D03*
X603787Y670197D03*
Y660748D03*
Y651299D03*
X570287Y687417D03*
X561437Y665417D03*
X559000Y741000D03*
X586087Y729617D03*
X570287Y699917D03*
X603000Y781000D03*
X592287Y752917D03*
X604000Y897000D03*
X592000Y900500D03*
X589500Y988000D03*
X571000D03*
X575000Y1057500D03*
X586500Y1061500D03*
X586000Y1046500D03*
X575000Y1046000D03*
X561337Y1120873D03*
X583487Y1100373D03*
X571787Y1092973D03*
X589137Y1100173D03*
X603787Y1122953D03*
Y1113504D03*
Y1104055D03*
X570287Y1140173D03*
Y1152673D03*
X567500Y1189500D03*
X586087Y1182373D03*
X592287Y1205673D03*
X590000Y1247000D03*
X567374Y1369303D03*
X572374D03*
X577374D03*
X582374D03*
X587374D03*
X592374D03*
X597374D03*
X602374D03*
X562374D03*
X609146Y5500D03*
X619146D03*
X614146D03*
X629146D03*
X639146D03*
X649146D03*
X654146D03*
X644146D03*
X634146D03*
X624146D03*
X613500Y66000D03*
X634500Y77000D03*
X629024Y107633D03*
X614967Y134777D03*
X606718Y168580D03*
X639537Y237161D03*
X608287Y245492D03*
Y235492D03*
X649500Y285000D03*
X608287Y275492D03*
X607961Y263934D03*
X650000Y322500D03*
X615287Y314114D03*
X649000Y429500D03*
X643000Y549500D03*
X620153Y511994D03*
X634388Y511957D03*
X638646Y515994D03*
X624411Y516031D03*
X615287Y594626D03*
X608287Y648248D03*
Y633248D03*
Y618248D03*
Y688248D03*
X639537Y689917D03*
X650659Y744673D03*
X608287Y728248D03*
Y718248D03*
Y698248D03*
X637326Y732212D03*
X650668Y720583D03*
X650711Y710495D03*
X631500Y774000D03*
X615287Y766870D03*
X642000Y889500D03*
X632000Y936000D03*
X654000Y911000D03*
X646500Y898500D03*
X634000Y988000D03*
X638500Y1046500D03*
X608287Y1071004D03*
X615287Y1047382D03*
X608287Y1101004D03*
Y1086004D03*
X643000Y1146173D03*
X608287Y1171004D03*
Y1151004D03*
Y1141004D03*
X651216Y1164051D03*
X615238Y1218951D03*
X608287Y1181004D03*
X650644Y1197038D03*
X650626Y1182447D03*
X617374Y1369303D03*
X622374D03*
X627374D03*
X632374D03*
X637374D03*
X642374D03*
X647374D03*
X652374D03*
X607374D03*
X612374D03*
X679146Y5500D03*
X689146D03*
X694146D03*
X684146D03*
X659146D03*
X669146D03*
X664146D03*
X674146D03*
X699146D03*
X700000Y60000D03*
X675000Y75500D03*
X697457Y107247D03*
X697483Y111500D03*
X661965Y106177D03*
X658500Y184500D03*
X695137Y189130D03*
X685545Y212806D03*
X689426Y236628D03*
X694500Y247161D03*
X670500Y254661D03*
X673500Y344000D03*
X698500Y415500D03*
X695500Y462500D03*
X670000Y531500D03*
X696000Y641717D03*
X694500Y687417D03*
X685550Y665417D03*
X670500Y707417D03*
X694500Y699917D03*
X691500Y778000D03*
X692500Y790500D03*
X678500Y776500D03*
X673500Y752000D03*
X696000Y1092973D03*
X685250Y1113673D03*
X667700Y1160173D03*
X694500Y1140173D03*
X692671Y1152747D03*
X668000Y1195000D03*
X680500Y1208500D03*
X698500Y1306500D03*
X667374Y1369303D03*
X672374D03*
X677374D03*
X682374D03*
X687374D03*
X692374D03*
X697374D03*
X702374D03*
X657374D03*
X662374D03*
X749146Y5500D03*
X709146D03*
X719146D03*
X729146D03*
X739146D03*
X744146D03*
X734146D03*
X724146D03*
X714146D03*
X704146D03*
X740000Y40000D03*
X720000D03*
Y60000D03*
X740000D03*
X724645Y138941D03*
X732500Y180492D03*
Y165492D03*
X728000Y207992D03*
Y198543D03*
X732100Y198373D03*
X707700Y194861D03*
X713350Y194661D03*
X728000Y217441D03*
X732500Y245492D03*
X731048Y238563D03*
X738361Y306612D03*
X732500Y275492D03*
Y265492D03*
X710300Y276861D03*
X716500Y300161D03*
X724000Y338500D03*
X748000Y368500D03*
X726000Y369000D03*
X732000Y374500D03*
Y383000D03*
X748500Y409000D03*
X721500Y462500D03*
X727500Y476000D03*
X724000Y583500D03*
X702500Y563000D03*
X739500Y594626D03*
X732500Y648248D03*
Y633248D03*
Y618248D03*
X713350Y647417D03*
X704500Y672000D03*
X728000Y670197D03*
X732500Y688248D03*
X728000Y660748D03*
Y651299D03*
X707700Y649117D03*
X732500Y728248D03*
Y718248D03*
Y698248D03*
X710300Y729617D03*
X748000Y783000D03*
X739500Y766870D03*
X716500Y752917D03*
X745000Y833000D03*
X704500Y795000D03*
X747656Y876717D03*
X709500Y894500D03*
X712000Y1046000D03*
X732500Y1071004D03*
X739500Y1047382D03*
X728000Y1122953D03*
Y1113504D03*
Y1104055D03*
X732500Y1101004D03*
Y1086004D03*
X713350Y1100173D03*
X707700Y1100373D03*
X716000Y1136000D03*
X732500Y1171004D03*
Y1151004D03*
Y1141004D03*
X739500Y1219626D03*
X732500Y1181004D03*
X710300Y1182373D03*
X716500Y1205673D03*
X747374Y1369303D03*
X742374D03*
X717374D03*
X722374D03*
X727374D03*
X732374D03*
X737374D03*
X707374D03*
X712374D03*
X795969Y-1374D03*
X759146Y5500D03*
X769146D03*
X774146D03*
X764146D03*
X754146D03*
X779146D03*
X789045Y11615D03*
X780000Y40000D03*
X760000D03*
Y60000D03*
X780000D03*
X752950Y213450D03*
X771500Y311000D03*
X764000Y439500D03*
X767500Y463500D03*
X772000Y479500D03*
X787000Y514000D03*
X798140Y630220D03*
X798210Y626440D03*
X798367Y622400D03*
X751750Y685300D03*
X793000Y828000D03*
Y851000D03*
X778000Y988500D03*
X762500D03*
X763000Y1075000D03*
X781000Y1373000D03*
X755500Y1374500D03*
X752500Y1370500D03*
X757287Y1380873D03*
Y1385873D03*
Y1390873D03*
Y1395873D03*
Y1400873D03*
Y1405873D03*
Y1410873D03*
Y1415873D03*
Y1420873D03*
X784000Y1443000D03*
X757287Y1425873D03*
Y1430873D03*
Y1435873D03*
Y1440873D03*
Y1445873D03*
X766156Y1462004D03*
X771156D03*
X790500Y1466500D03*
X786000Y1463500D03*
X756287Y1459264D03*
Y1454264D03*
X779547Y1463004D03*
X792902Y1477964D03*
Y1487964D03*
Y1497964D03*
Y1507964D03*
Y1517964D03*
Y1512964D03*
Y1472964D03*
Y1482964D03*
Y1492964D03*
Y1502964D03*
Y1562964D03*
Y1527964D03*
Y1537964D03*
Y1547964D03*
Y1557964D03*
Y1567964D03*
Y1522964D03*
Y1532964D03*
Y1542964D03*
Y1552964D03*
Y1612964D03*
Y1602964D03*
Y1592964D03*
Y1582964D03*
Y1572964D03*
Y1577964D03*
Y1587964D03*
Y1597964D03*
Y1607964D03*
X797902Y1652964D03*
X792902D03*
Y1642964D03*
Y1632964D03*
Y1622964D03*
Y1627964D03*
Y1637964D03*
Y1647964D03*
Y1617964D03*
X845961Y61762D03*
Y56762D03*
Y52762D03*
X846000Y116500D03*
X811500Y372000D03*
X800000Y400000D03*
X811500Y469500D03*
X846400Y469300D03*
X839000Y541000D03*
X839500Y560000D03*
X800867Y619400D03*
X803367Y622400D03*
X827500Y922500D03*
X839414Y1520763D03*
X833859Y1594095D03*
Y1608268D03*
X840945Y1598032D03*
X826772D03*
X840945Y1612205D03*
X826772D03*
X833859Y1622441D03*
Y1636614D03*
Y1650788D03*
X840945Y1626378D03*
X826772D03*
X840945Y1640551D03*
X826772D03*
X872642Y-140575D03*
Y-135575D03*
Y-130575D03*
Y-125575D03*
X890264Y-147256D03*
X880264D03*
X875264D03*
X885264D03*
X895264D03*
X882000Y-105500D03*
X872642Y-80575D03*
Y-120575D03*
Y-115575D03*
Y-110575D03*
Y-105575D03*
Y-100575D03*
Y-95575D03*
Y-90575D03*
Y-85575D03*
Y-30575D03*
Y-35575D03*
Y-40575D03*
Y-45575D03*
Y-50575D03*
Y-55575D03*
Y-60575D03*
Y-65575D03*
Y-70575D03*
Y-75575D03*
Y-20575D03*
Y-25575D03*
X885046Y20384D03*
X861101Y66680D03*
X862099Y61626D03*
Y56626D03*
X861961Y52762D03*
X852769Y66957D03*
X848769D03*
X856769D03*
X853961Y52762D03*
X849961D03*
X857961D03*
X874244Y37026D03*
Y44935D03*
X852769Y74957D03*
X856769D03*
X861142Y71026D03*
X852810Y71303D03*
X856810D03*
X853900Y89701D03*
X888500Y260500D03*
X850500Y266000D03*
X866000Y315000D03*
X856500Y373000D03*
X855500Y499500D03*
X871487Y463589D03*
X860092Y542405D03*
X867500Y643000D03*
X877000Y664500D03*
X868500Y665000D03*
X885600Y824400D03*
X867663Y818831D03*
X885301Y1358557D03*
X884746Y1350438D03*
X873495Y1370213D03*
X885300Y1371050D03*
X877300Y1432400D03*
X886500Y1432500D03*
X893050Y1489500D03*
X868791Y1478782D03*
X855092Y1535821D03*
X866621Y1544206D03*
X876378Y1594095D03*
X862205D03*
X848032D03*
X876378Y1608268D03*
X862205D03*
X848032D03*
X890552Y1598032D03*
X869292D03*
X855118D03*
X869292Y1612205D03*
X855118D03*
X876378Y1622441D03*
X862205D03*
X848032D03*
X876378Y1636614D03*
X862205D03*
X848032D03*
X876378Y1650788D03*
X862205D03*
X848032D03*
X869292Y1626378D03*
X855118D03*
X869292Y1640551D03*
X855118D03*
X910500Y-137500D03*
X940264Y-147256D03*
X930264D03*
X925264D03*
X935264D03*
X920264D03*
X910264D03*
X900264D03*
X905264D03*
X915264D03*
X902000Y-58000D03*
X909000Y89000D03*
X898000Y133000D03*
X911000Y305500D03*
X898000Y268000D03*
X915000Y879000D03*
X926185Y928342D03*
X924974Y933041D03*
X914876Y901029D03*
X937621Y915324D03*
X924563Y962945D03*
X919759Y970868D03*
X938009Y987330D03*
X941868Y952101D03*
X916446Y1035438D03*
X941640Y995820D03*
X929257Y1035883D03*
X932564Y1346100D03*
X904941Y1456941D03*
X897638Y1594095D03*
X960264Y-147256D03*
X950264D03*
X955264D03*
X965264D03*
X945264D03*
X990264D03*
X980264D03*
X970264D03*
X975264D03*
X985264D03*
X975500Y11500D03*
X974000Y402000D03*
Y523000D03*
X985500Y613500D03*
X978000Y677000D03*
X981580Y932678D03*
X976580Y986180D03*
X959400Y960300D03*
X987970Y1004157D03*
X955700Y1030700D03*
X977400Y1157900D03*
X977500Y1182300D03*
X962500Y1298500D03*
X946300Y1499300D03*
X975813Y1556916D03*
Y1545916D03*
X1010264Y-147256D03*
X1000264D03*
X1005264D03*
X1015264D03*
X995264D03*
X1040264D03*
X1030264D03*
X1020264D03*
X1025264D03*
X1035264D03*
X1015582Y-69800D03*
X1014800Y-62100D03*
X999300Y-64400D03*
X1009100Y-48600D03*
X1035000Y-66800D03*
X1022618Y-36900D03*
X1023300Y-44200D03*
X1032053Y-34953D03*
X1038712Y-34812D03*
X1017600Y63600D03*
Y58900D03*
Y54200D03*
X993000Y108000D03*
X1036003Y93543D03*
X1038503Y97543D03*
X1033503D03*
Y102543D03*
Y107543D03*
Y112543D03*
X993000Y157000D03*
Y329000D03*
X998000Y378000D03*
X995000Y455000D03*
Y488000D03*
X1018322Y545207D03*
X1018300Y550000D03*
X993000Y635000D03*
X1025000Y817000D03*
X1028472Y834829D03*
X1027063Y850703D03*
X1014891Y943357D03*
X1013713Y974651D03*
X997694Y974940D03*
X1012494Y1033840D03*
X1018000Y1076500D03*
X1031400Y1124700D03*
X1019000Y1178000D03*
X1013400Y1137500D03*
X1021991Y1141526D03*
X1004294Y1137600D03*
X997500Y1192500D03*
X1006800Y1191200D03*
X1032500Y1248000D03*
X993500Y1317000D03*
X1031000Y1350500D03*
X1031474Y1354526D03*
X1060264Y-147256D03*
X1050264D03*
X1055264D03*
X1065264D03*
X1045264D03*
X1080264D03*
X1070264D03*
X1075264D03*
X1085264D03*
X1065621Y-85082D03*
X1084200Y-82300D03*
X1074400Y-81000D03*
X1070500Y-67900D03*
X1074400Y-39100D03*
X1079600Y-50700D03*
X1087700Y-37886D03*
X1045800Y-75936D03*
X1058333Y-72770D03*
X1061325Y-40378D03*
X1054625Y-40278D03*
X1078500Y99000D03*
X1043703Y112543D03*
Y107543D03*
Y102543D03*
X1041003Y93543D03*
X1043703Y97543D03*
X1078500Y135500D03*
X1043500Y310500D03*
X1048500Y346000D03*
X1058500Y368500D03*
X1045000Y364000D03*
X1042833Y434409D03*
X1047000Y492000D03*
X1079000Y477000D03*
X1058000D03*
X1045106Y561249D03*
X1058000Y616000D03*
X1073000Y676000D03*
X1047000Y751000D03*
X1045163Y840400D03*
X1082000Y815500D03*
X1054000Y866000D03*
X1075500Y848000D03*
X1072000Y1035000D03*
X1052000Y1054000D03*
X1054080Y1077680D03*
X1087700Y1125800D03*
X1078098Y1652768D03*
X1073098D03*
X1083098D03*
X1088098D03*
X1110264Y-147256D03*
X1100264D03*
X1090264D03*
X1105264D03*
X1095264D03*
X1130264D03*
X1120264D03*
X1115264D03*
X1125264D03*
X1135264D03*
X1134500Y-103500D03*
X1115000Y-77500D03*
X1097600Y-82462D03*
X1107700Y-76800D03*
X1114400Y-55662D03*
X1093900Y-64500D03*
X1113300Y-44100D03*
X1137446Y1024025D03*
Y1009852D03*
Y995679D03*
Y1038198D03*
X1124100Y1125100D03*
X1137446Y1167343D03*
Y1224036D03*
Y1209863D03*
Y1195690D03*
Y1181516D03*
Y1266556D03*
Y1252383D03*
Y1238209D03*
Y1309076D03*
Y1323249D03*
Y1294902D03*
Y1280729D03*
Y1365769D03*
Y1351595D03*
Y1337422D03*
Y1394115D03*
Y1408288D03*
Y1379942D03*
X1093098Y1652768D03*
X1133098D03*
X1123098D03*
X1113098D03*
X1103098D03*
X1108098D03*
X1118098D03*
X1128098D03*
X1098098D03*
X1170264Y-147256D03*
X1155264D03*
X1175602Y-137594D03*
Y-127594D03*
X1160264Y-147256D03*
X1150264D03*
X1140264D03*
X1145264D03*
X1175602Y-132594D03*
Y-142594D03*
X1165264Y-147256D03*
X1175602Y-117594D03*
Y-107594D03*
Y-97594D03*
Y-87594D03*
Y-77594D03*
Y-82594D03*
Y-92594D03*
Y-102594D03*
Y-112594D03*
Y-122594D03*
X1139500Y-58500D03*
X1150000Y-63000D03*
X1175602Y-67594D03*
Y-57594D03*
Y-47594D03*
Y-37594D03*
Y-32594D03*
Y-42594D03*
Y-52594D03*
Y-62594D03*
Y-72594D03*
Y-17594D03*
Y-27594D03*
X1180500Y4000D03*
X1176500Y-500D03*
X1175602Y-22594D03*
Y-12594D03*
Y-7594D03*
X1184088Y101360D03*
X1184141Y96794D03*
X1177500Y153500D03*
X1173500Y397000D03*
X1156500Y467000D03*
X1166500Y635000D03*
X1156500Y619000D03*
X1176835Y618934D03*
X1156500Y650000D03*
X1181000Y814000D03*
X1156500Y813000D03*
X1179000Y829500D03*
X1166500D03*
X1158500Y868500D03*
X1144580Y1078680D03*
X1172564Y1118373D03*
X1162000Y1371500D03*
X1169783Y1369303D03*
X1179783D03*
X1174783D03*
X1184783D03*
X1158673Y1417067D03*
Y1407067D03*
Y1397067D03*
Y1387067D03*
Y1377067D03*
Y1412067D03*
Y1402067D03*
Y1392067D03*
Y1382067D03*
Y1422067D03*
Y1442067D03*
Y1452067D03*
X1158500Y1468500D03*
X1158673Y1457067D03*
Y1447067D03*
Y1437067D03*
Y1427067D03*
Y1462067D03*
Y1432067D03*
X1153000Y1496000D03*
X1161000Y1474500D03*
X1166673Y1477941D03*
X1171673D03*
X1181673D03*
X1176673D03*
X1163000Y1612000D03*
X1141000Y1632000D03*
X1143098Y1652768D03*
X1183098D03*
X1173098D03*
X1163098D03*
X1153098D03*
X1158098D03*
X1168098D03*
X1178098D03*
X1138098D03*
X1148098D03*
X1228500Y12500D03*
X1191382Y5500D03*
X1196382D03*
X1186382D03*
X1201382D03*
X1211382D03*
X1221382D03*
X1231382D03*
X1226382D03*
X1216382D03*
X1206382D03*
X1204768Y64368D03*
X1199768D03*
X1209768D03*
X1204068Y50368D03*
Y45368D03*
X1203768Y60568D03*
Y55568D03*
X1224000Y104000D03*
X1199768Y69368D03*
X1204768D03*
X1209768D03*
X1204768Y85368D03*
X1199768D03*
X1209768D03*
Y89368D03*
X1199768D03*
X1204768D03*
X1186500Y220500D03*
X1224800Y225200D03*
X1219917Y239646D03*
X1232500Y541000D03*
X1197868Y730300D03*
X1194268D03*
Y723100D03*
Y726700D03*
X1197868Y723100D03*
Y726700D03*
X1192068Y712300D03*
X1195668D03*
X1192068Y715900D03*
X1195668D03*
Y719500D03*
X1192068D03*
X1188000Y753000D03*
X1192000Y869000D03*
X1232700Y950400D03*
X1229691Y1148580D03*
X1214500Y1320500D03*
X1220500Y1311000D03*
X1199783Y1369303D03*
X1209783D03*
X1219783D03*
X1229783D03*
X1189783D03*
X1224783D03*
X1214783D03*
X1204783D03*
X1194783D03*
X1194000Y1499000D03*
X1191673Y1477941D03*
X1201673D03*
X1214972Y1482642D03*
Y1517642D03*
Y1487642D03*
Y1497642D03*
Y1507642D03*
Y1512642D03*
Y1502642D03*
Y1492642D03*
X1206673Y1477941D03*
X1196673D03*
X1186673D03*
X1211673D03*
X1214972Y1567642D03*
Y1527642D03*
Y1537642D03*
Y1547642D03*
Y1557642D03*
Y1562642D03*
Y1552642D03*
Y1542642D03*
Y1532642D03*
Y1522642D03*
Y1577642D03*
Y1587642D03*
Y1597642D03*
Y1607642D03*
Y1612642D03*
Y1602642D03*
Y1592642D03*
Y1582642D03*
Y1572642D03*
Y1617642D03*
Y1627642D03*
Y1637642D03*
X1213098Y1652768D03*
X1193098D03*
X1203098D03*
X1208098D03*
X1214972Y1642642D03*
Y1632642D03*
X1188098Y1652768D03*
X1198098D03*
X1214972Y1622642D03*
Y1647642D03*
X1240500Y20000D03*
X1251382Y5500D03*
X1261382D03*
X1271382D03*
X1281382D03*
X1276382D03*
X1266382D03*
X1256382D03*
X1241382D03*
X1246382D03*
X1236382D03*
X1254000Y105000D03*
X1281500Y103500D03*
X1278900Y182823D03*
X1266400D03*
X1278421Y205974D03*
X1281603Y203340D03*
X1282106Y180492D03*
X1280800Y167200D03*
X1282287Y243489D03*
X1277606Y217441D03*
X1282106Y235492D03*
X1248193Y242618D03*
X1255600Y237300D03*
X1273200Y263700D03*
X1276200Y277400D03*
X1280000Y430000D03*
X1235796Y517450D03*
X1250011Y516707D03*
X1282106Y648248D03*
Y633248D03*
Y618248D03*
X1253800Y689600D03*
X1277606Y670197D03*
X1282106Y688248D03*
X1277606Y660748D03*
Y651299D03*
X1282106Y728248D03*
Y718248D03*
Y698248D03*
X1250475Y969248D03*
X1279081Y1071085D03*
X1277606Y1122953D03*
Y1113504D03*
Y1104055D03*
X1282106Y1101004D03*
Y1086004D03*
X1251250Y1141700D03*
X1282106Y1171004D03*
Y1151004D03*
Y1141004D03*
X1246557Y1148155D03*
X1249600Y1155800D03*
X1282106Y1181004D03*
X1257000Y1300000D03*
X1263500Y1318500D03*
X1249783Y1369303D03*
X1259783D03*
X1269783D03*
X1279783D03*
X1239783D03*
X1274783D03*
X1264783D03*
X1254783D03*
X1234783D03*
X1244783D03*
X1319000Y12000D03*
X1301382Y5500D03*
X1311382D03*
X1296382D03*
X1316382D03*
X1306382D03*
X1291382D03*
X1286382D03*
X1326382D03*
X1321382D03*
X1309000Y45500D03*
X1318500Y34500D03*
X1319100Y78800D03*
X1323521Y79179D03*
X1312999Y107280D03*
X1317661Y107896D03*
X1299569Y84272D03*
X1304563Y84309D03*
X1289000Y145400D03*
X1302074Y183779D03*
X1311200Y172661D03*
X1304293Y165909D03*
X1315838Y188804D03*
X1297507Y195492D03*
X1298700Y272800D03*
X1298500Y302900D03*
X1305000Y299400D03*
X1313000Y302900D03*
X1313915Y263541D03*
X1289000Y309500D03*
X1311000Y321000D03*
X1303500Y434000D03*
X1287000Y456000D03*
X1310000Y597000D03*
X1289106Y594626D03*
X1303800Y636417D03*
X1311200Y625417D03*
X1307500Y615417D03*
X1315400Y648017D03*
X1302500Y718917D03*
X1314000Y717417D03*
X1298500Y752417D03*
X1305000D03*
X1313000D03*
X1289106Y766870D03*
X1305000Y1041500D03*
X1289114Y1048624D03*
X1311200Y1078173D03*
X1305100Y1068173D03*
X1303800Y1089173D03*
X1315300Y1100773D03*
X1302500Y1171673D03*
X1313950Y1165990D03*
X1300065Y1206008D03*
X1305000Y1205173D03*
X1313000D03*
X1289106Y1219626D03*
X1299783Y1369303D03*
X1309783D03*
X1319783D03*
X1329783D03*
X1289783D03*
X1324783D03*
X1314783D03*
X1304783D03*
X1294783D03*
X1284783D03*
X1363579Y19821D03*
Y14821D03*
Y9821D03*
X1351382Y5500D03*
X1356382D03*
X1346382D03*
X1336382D03*
X1341382D03*
X1331382D03*
X1357500Y43500D03*
X1347500Y21000D03*
X1363579Y44821D03*
Y39821D03*
Y34821D03*
Y29821D03*
Y24821D03*
X1374000Y64500D03*
X1363579Y51618D03*
X1332500Y56500D03*
X1351201Y90099D03*
X1332934Y137712D03*
X1377463Y237100D03*
X1372000Y335000D03*
X1338000Y546500D03*
X1346363Y516578D03*
X1332148Y517321D03*
X1337500Y576500D03*
X1372272Y573560D03*
X1375463Y689917D03*
X1339500Y794000D03*
X1344000Y987500D03*
X1362000Y987000D03*
X1331070Y966090D03*
X1348796Y969488D03*
X1368935Y1123365D03*
X1365461Y1136100D03*
X1375463Y1142673D03*
X1364713Y1143791D03*
X1349783Y1369303D03*
X1359783D03*
X1369783D03*
X1339783D03*
X1374783D03*
X1364783D03*
X1354783D03*
X1344783D03*
X1334783D03*
X1413268Y146062D03*
X1401819Y207992D03*
X1394705Y195413D03*
X1406319Y180492D03*
X1405100Y166000D03*
X1403963Y245492D03*
X1385051Y218684D03*
X1406000Y236700D03*
X1426713Y266161D03*
X1426400Y307400D03*
X1406319Y275492D03*
Y265492D03*
X1400000Y406000D03*
X1427000Y380000D03*
X1425000Y480000D03*
X1405000D03*
Y460000D03*
X1385000Y480000D03*
X1396500Y511000D03*
X1383500Y509500D03*
X1418493Y531407D03*
X1425600Y544600D03*
X1418507Y517007D03*
X1413319Y594626D03*
X1406319Y648248D03*
Y633248D03*
Y618248D03*
X1421500Y664000D03*
X1401819Y670197D03*
X1406319Y688248D03*
X1401819Y660748D03*
Y651299D03*
X1426713Y718917D03*
X1406319Y728248D03*
Y718248D03*
Y698248D03*
X1422713Y752417D03*
X1398245Y766870D03*
X1395000Y791500D03*
X1390000Y955500D03*
X1390500Y1048000D03*
X1406319Y1071004D03*
X1413319Y1047382D03*
X1406319Y1086004D03*
Y1101004D03*
X1401819Y1104055D03*
X1385494Y1113504D03*
X1401819Y1122953D03*
X1406319Y1141004D03*
Y1151004D03*
Y1171004D03*
X1426713Y1171673D03*
X1406319Y1181004D03*
X1413319Y1219626D03*
X1422713Y1205173D03*
X1413000Y1241500D03*
X1387000Y1243500D03*
X1386500Y1258000D03*
X1418000Y1291500D03*
X1400000Y1320000D03*
X1420000D03*
X1399783Y1369303D03*
X1409783D03*
X1419783D03*
X1379783D03*
X1389783D03*
X1404783D03*
X1414783D03*
X1424783D03*
X1394783D03*
X1384783D03*
X1431713Y162661D03*
X1428013Y185956D03*
X1445994Y174086D03*
X1440300Y188000D03*
X1438186Y261287D03*
X1463000Y307000D03*
X1439300Y301500D03*
X1429800Y302500D03*
X1447170Y337890D03*
X1466500Y338100D03*
X1441770Y365790D03*
X1461100Y366000D03*
X1441970Y403990D03*
X1461300Y404200D03*
X1439500Y421500D03*
X1440000Y460000D03*
X1449576Y495482D03*
X1468605Y493549D03*
X1457200Y549600D03*
X1470700Y522100D03*
X1456439Y515000D03*
X1448261D03*
X1435200D03*
X1443700D03*
X1460200D03*
X1452200D03*
X1465700D03*
X1439200D03*
X1459200Y579600D03*
X1452200D03*
X1428013Y636417D03*
X1435413Y625417D03*
X1431713Y615417D03*
X1439713Y647917D03*
X1449000Y698000D03*
X1438087Y713756D03*
X1429213Y752417D03*
X1437213D03*
X1432000Y831000D03*
X1459500Y814000D03*
X1450500Y802500D03*
X1459500Y796500D03*
X1473000Y798000D03*
X1433500Y864500D03*
X1457500Y987500D03*
X1440000Y986500D03*
X1473008Y969646D03*
X1458967Y969535D03*
X1433500Y1044000D03*
X1456000D03*
X1435413Y1078173D03*
X1431713Y1068173D03*
X1428013Y1089173D03*
X1439713Y1100773D03*
X1438213Y1170173D03*
X1429213Y1205173D03*
X1437213D03*
X1458000Y1265500D03*
X1460000Y1300000D03*
Y1320000D03*
X1440000D03*
X1449783Y1369303D03*
X1459783D03*
X1469783D03*
X1429783D03*
X1439783D03*
X1444783D03*
X1454783D03*
X1464783D03*
X1474783D03*
X1434783D03*
X1515450Y181700D03*
X1502950D03*
X1498900Y235800D03*
X1505000Y378500D03*
X1520000Y421500D03*
X1481938Y512568D03*
X1485932Y522335D03*
X1494462Y692179D03*
X1515000Y789000D03*
X1520000Y776000D03*
X1499500Y774000D03*
Y831000D03*
X1510500Y878000D03*
X1510000Y860500D03*
X1512500Y949000D03*
X1508500Y1028500D03*
Y1050500D03*
X1488500Y1096000D03*
X1489096Y1131456D03*
X1489108Y1121674D03*
X1499675Y1142673D03*
X1489333Y1147664D03*
X1480000Y1320000D03*
X1499783Y1369303D03*
X1509783D03*
X1519783D03*
X1479783D03*
X1489783D03*
X1494783D03*
X1484783D03*
X1504783D03*
X1514783D03*
X1565555Y16517D03*
X1568030Y5500D03*
X1565555Y21517D03*
Y26517D03*
Y31517D03*
Y36517D03*
Y41517D03*
X1557000Y64500D03*
X1561500Y62000D03*
X1564000Y57500D03*
X1564555Y52124D03*
X1525336Y149369D03*
X1555925Y162661D03*
X1545383Y164116D03*
X1560000Y140000D03*
X1552225Y183661D03*
X1559625Y172661D03*
X1563925Y195261D03*
X1526031Y207992D03*
Y198543D03*
X1530531Y195492D03*
Y180492D03*
Y245492D03*
X1526031Y217441D03*
X1530142Y238021D03*
X1550925Y266161D03*
X1546925Y299661D03*
X1553425D03*
X1561425D03*
X1562425Y264661D03*
X1530531Y275492D03*
Y265492D03*
X1537531Y314114D03*
X1545000Y455000D03*
X1560000D03*
X1525000D03*
X1545000Y475000D03*
X1560000D03*
Y500000D03*
Y525000D03*
X1552000Y584500D03*
X1566000Y595000D03*
X1537531Y594626D03*
X1552225Y636417D03*
X1559625Y625417D03*
X1555925Y615417D03*
X1530531Y648248D03*
Y633248D03*
Y618248D03*
X1558925Y650017D03*
X1526031Y670197D03*
X1530531Y688248D03*
X1526031Y660748D03*
Y651299D03*
X1550925Y718917D03*
X1562425Y717417D03*
X1530531Y728248D03*
Y718248D03*
Y698248D03*
X1555000Y770000D03*
X1546925Y752417D03*
X1553425D03*
X1561425D03*
X1537531Y766870D03*
X1525000Y878000D03*
X1564500Y931000D03*
X1548500Y933000D03*
X1564000Y949000D03*
X1552500Y1028000D03*
X1557500Y1043500D03*
X1537531Y1047382D03*
X1559625Y1078173D03*
X1555925Y1068173D03*
X1530531Y1071004D03*
X1552225Y1089173D03*
X1526031Y1122953D03*
Y1113504D03*
Y1104055D03*
X1530531Y1101004D03*
Y1086004D03*
X1550925Y1171673D03*
X1552575Y1139700D03*
X1562425Y1170173D03*
X1530531Y1171004D03*
Y1151004D03*
X1528723Y1138918D03*
X1546898Y1204827D03*
X1553425Y1208897D03*
X1561425Y1205173D03*
X1537879Y1219626D03*
X1530531Y1181004D03*
X1549783Y1369303D03*
X1559783D03*
X1569783D03*
X1529783D03*
X1539783D03*
X1524783D03*
X1534783D03*
X1544783D03*
X1554783D03*
X1564783D03*
X1600000Y20000D03*
X1620000D03*
X1580000D03*
X1603030Y5500D03*
X1613030D03*
X1573030D03*
X1583030D03*
X1593030D03*
X1618030D03*
X1608030D03*
X1598030D03*
X1588030D03*
X1578030D03*
X1600000Y60000D03*
X1620000Y40000D03*
X1600000D03*
X1580000D03*
Y60000D03*
X1620000Y100000D03*
X1600000Y80000D03*
X1620000D03*
X1580000D03*
X1620000Y140000D03*
Y120000D03*
X1585757Y134147D03*
X1607000Y199000D03*
X1595500Y258500D03*
X1621100Y240561D03*
X1608000Y256000D03*
X1600000Y340000D03*
X1620000D03*
Y320000D03*
X1600000D03*
X1579500Y331000D03*
X1597245Y516662D03*
X1583030Y517405D03*
X1573000Y565500D03*
X1580000Y780000D03*
X1576500Y928500D03*
X1597221Y969572D03*
X1583180Y969461D03*
X1596000Y990000D03*
X1611500Y1078000D03*
X1593000Y1043500D03*
X1593500Y1185500D03*
X1581500Y1240000D03*
X1600000Y1320000D03*
X1614783Y1369303D03*
X1604783D03*
X1599783D03*
X1609783D03*
X1619783D03*
X1579783D03*
X1589783D03*
X1574783D03*
X1584783D03*
X1594783D03*
X1640000Y20000D03*
X1660000D03*
X1653030Y5500D03*
X1663030D03*
X1623030D03*
X1633030D03*
X1643030D03*
X1668030D03*
X1658030D03*
X1648030D03*
X1638030D03*
X1628030D03*
X1640000Y60000D03*
X1660000D03*
Y40000D03*
X1640000D03*
Y100000D03*
X1660000D03*
X1640000Y80000D03*
X1660000D03*
Y120000D03*
X1640000D03*
X1661744Y141870D03*
X1650244Y207992D03*
Y198543D03*
X1654744Y195492D03*
Y180492D03*
Y165492D03*
Y245492D03*
X1650244Y217441D03*
X1654744Y235492D03*
X1652387Y277343D03*
X1653789Y267766D03*
X1639000Y320000D03*
X1640000Y340000D03*
X1660000D03*
X1661744Y314114D03*
X1660000Y400000D03*
X1640000Y360000D03*
X1660000Y440000D03*
Y480000D03*
X1640000D03*
Y460000D03*
X1660000D03*
X1640000Y500000D03*
X1660000D03*
Y520000D03*
X1640000D03*
X1660000Y540000D03*
X1640000D03*
Y560000D03*
X1660000D03*
X1661744Y594626D03*
X1654744Y648248D03*
Y633248D03*
Y618248D03*
X1623888Y689917D03*
X1652962Y670204D03*
X1654744Y688248D03*
X1650244Y660748D03*
Y651299D03*
X1637000Y729000D03*
X1638000Y740000D03*
X1654744Y728248D03*
Y718248D03*
Y698248D03*
X1630000Y780000D03*
Y760000D03*
X1661744Y766870D03*
X1625000Y800000D03*
X1651500Y913500D03*
X1650000Y950000D03*
Y980000D03*
X1653500Y1016500D03*
X1650000Y1000000D03*
X1632000Y1049500D03*
X1654744Y1071004D03*
X1661744Y1047382D03*
X1650244Y1122953D03*
Y1113504D03*
Y1104055D03*
X1654744Y1101004D03*
Y1086004D03*
X1627563Y1132075D03*
X1627802Y1118949D03*
X1627769Y1110037D03*
X1635688Y1141158D03*
X1650841Y1168660D03*
X1654744Y1151004D03*
Y1141004D03*
X1627197Y1143044D03*
X1661744Y1219626D03*
X1668378Y1181004D03*
X1640000Y1260000D03*
X1660000D03*
X1640000Y1320000D03*
Y1300000D03*
X1660000Y1320000D03*
Y1300000D03*
Y1280000D03*
X1640000D03*
X1664783Y1369303D03*
X1654783D03*
X1644783D03*
X1634783D03*
X1624783D03*
X1649783D03*
X1659783D03*
X1629783D03*
X1639783D03*
X1700000Y20000D03*
X1680000D03*
X1703030Y5500D03*
X1713030D03*
X1673030D03*
X1683030D03*
X1693030D03*
X1718030D03*
X1708030D03*
X1698030D03*
X1688030D03*
X1678030D03*
X1700000Y60000D03*
Y40000D03*
X1680000Y60000D03*
Y40000D03*
Y100000D03*
Y80000D03*
X1700000Y100000D03*
Y80000D03*
Y140000D03*
Y120000D03*
X1680000D03*
X1679500Y144000D03*
X1680138Y162661D03*
X1676438Y183661D03*
X1683838Y172661D03*
X1688138Y195261D03*
X1675475Y267424D03*
X1671138Y299661D03*
X1677638D03*
X1685638D03*
X1686638Y264661D03*
X1678500Y320000D03*
X1700000Y400000D03*
X1680000Y380000D03*
X1700000Y360000D03*
X1680000Y440000D03*
Y420000D03*
X1700000Y440000D03*
Y420000D03*
Y460000D03*
X1680000Y480000D03*
Y460000D03*
Y500000D03*
Y520000D03*
X1700000Y540000D03*
X1680000D03*
X1707495Y517152D03*
X1700000Y560000D03*
X1680000D03*
X1676438Y636417D03*
X1683838Y625417D03*
X1680138Y615417D03*
X1688138Y648017D03*
X1675138Y718917D03*
X1686638Y717417D03*
X1710000Y770000D03*
Y785000D03*
X1685000Y770000D03*
X1671138Y752417D03*
X1677638D03*
X1685638D03*
X1709000Y915000D03*
X1687000Y905500D03*
X1716500Y943500D03*
X1706000Y1022000D03*
X1683838Y1078173D03*
X1680138Y1068173D03*
X1688138Y1100773D03*
X1676438Y1089173D03*
X1686638Y1170173D03*
X1675138Y1171673D03*
X1685638Y1205173D03*
X1677638D03*
X1671138D03*
X1680000Y1240000D03*
X1700000Y1260000D03*
X1680000D03*
X1700000Y1320000D03*
Y1300000D03*
Y1280000D03*
X1680000Y1320000D03*
Y1300000D03*
Y1280000D03*
X1714783Y1369303D03*
X1704783D03*
X1694783D03*
X1684783D03*
X1674783D03*
X1699783D03*
X1709783D03*
X1669783D03*
X1679783D03*
X1689783D03*
X1760000Y20000D03*
X1740000D03*
X1720000D03*
X1753030Y5500D03*
X1763030D03*
X1723030D03*
X1733030D03*
X1743030D03*
X1758030D03*
X1748030D03*
X1738030D03*
X1728030D03*
X1760000Y60000D03*
Y40000D03*
X1740000D03*
Y60000D03*
X1720000Y40000D03*
Y60000D03*
X1740000Y100000D03*
X1760000D03*
X1740000Y80000D03*
X1760000D03*
X1720000Y100000D03*
Y80000D03*
X1740000Y140000D03*
X1760000Y120000D03*
X1740000D03*
X1720000Y140000D03*
Y120000D03*
X1728500Y249500D03*
X1746600Y240561D03*
X1760486Y217441D03*
X1763500Y288000D03*
X1720000Y300000D03*
Y280000D03*
Y340000D03*
X1760000D03*
X1740000Y320000D03*
X1760000Y440000D03*
Y420000D03*
Y500000D03*
Y480000D03*
Y460000D03*
X1740000Y540000D03*
X1760000D03*
Y520000D03*
X1721710Y516409D03*
X1745000Y670000D03*
Y690000D03*
Y660000D03*
X1730000Y690000D03*
Y670000D03*
Y730000D03*
Y710000D03*
X1735000Y785000D03*
X1730000Y775000D03*
Y750000D03*
X1725000Y800000D03*
X1718000Y876000D03*
X1759884Y969161D03*
X1742001Y965464D03*
X1755000Y1045000D03*
X1725000D03*
X1745000Y1100000D03*
X1759055Y1113504D03*
X1736725Y1123446D03*
X1748100Y1142673D03*
X1736871Y1158178D03*
X1736941Y1141871D03*
X1728000Y1204500D03*
X1720000Y1320000D03*
X1760000D03*
X1753000Y1302000D03*
X1764783Y1369303D03*
X1754783D03*
X1744783D03*
X1734783D03*
X1724783D03*
X1749783D03*
X1759783D03*
X1719783D03*
X1729783D03*
X1739783D03*
X1778030Y5500D03*
X1793030D03*
X1803030D03*
X1813030D03*
X1808030D03*
X1798030D03*
X1783030D03*
X1788030D03*
X1773030D03*
X1768030D03*
X1780000Y60000D03*
Y40000D03*
X1800000Y100000D03*
Y80000D03*
X1780000Y100000D03*
Y80000D03*
X1800000Y120000D03*
X1780000D03*
X1785956Y141870D03*
X1804350Y162661D03*
X1801988Y183904D03*
X1808050Y172661D03*
X1812350Y195261D03*
X1774456Y207992D03*
Y198543D03*
X1778956Y195492D03*
Y180492D03*
X1775140Y165728D03*
X1778956Y245492D03*
Y235492D03*
X1799350Y266161D03*
X1795350Y299661D03*
X1801850D03*
X1809850D03*
X1810850Y264661D03*
X1778956Y275492D03*
Y265492D03*
X1785956Y314114D03*
X1800000Y440000D03*
X1780000D03*
X1800000Y500000D03*
X1780000D03*
X1800000Y480000D03*
Y460000D03*
X1780000Y480000D03*
Y460000D03*
X1800000Y540000D03*
X1780000D03*
X1800000Y520000D03*
X1780000D03*
X1800000Y560000D03*
X1785956Y594626D03*
X1800650Y636417D03*
X1808050Y625417D03*
X1804350Y615417D03*
X1812350Y648017D03*
X1778956Y648248D03*
Y633248D03*
Y618248D03*
X1774456Y670197D03*
X1778956Y688248D03*
X1774456Y660748D03*
Y651299D03*
X1799326Y717506D03*
X1811474Y717423D03*
X1778956Y728248D03*
Y718248D03*
Y698248D03*
X1766721Y716500D03*
X1795468Y752594D03*
X1801968D03*
X1809968D03*
X1785956Y766870D03*
X1773500Y879500D03*
X1771000Y944500D03*
X1799000Y945500D03*
X1788361Y964676D03*
X1799051Y963346D03*
X1785956Y1047382D03*
X1808050Y1078173D03*
X1800750Y1067973D03*
X1778956Y1071004D03*
X1800650Y1089173D03*
X1811968Y1100773D03*
X1774456Y1122953D03*
Y1104055D03*
X1778956Y1101004D03*
Y1086004D03*
X1799350Y1171673D03*
X1810850Y1170173D03*
X1778956Y1171004D03*
Y1151004D03*
Y1141004D03*
X1795350Y1205173D03*
X1801850D03*
X1809850D03*
X1785956Y1219626D03*
X1778956Y1181004D03*
X1772111Y1232695D03*
X1804783Y1369303D03*
X1794783D03*
X1784783D03*
X1774783D03*
X1799783D03*
X1809783D03*
X1769783D03*
X1779783D03*
X1789783D03*
X1843030Y5500D03*
X1853030D03*
X1863030D03*
X1838030D03*
X1858030D03*
X1848030D03*
X1823030D03*
X1833030D03*
X1828030D03*
X1818030D03*
X1860000Y60000D03*
Y80000D03*
Y100000D03*
X1840000D03*
X1820000D03*
X1860000Y140000D03*
Y120000D03*
X1840000D03*
X1820000Y140000D03*
Y120000D03*
X1856219Y212661D03*
X1841169Y254661D03*
X1840000Y340000D03*
Y320000D03*
X1860000D03*
X1820000D03*
Y440000D03*
Y480000D03*
Y460000D03*
X1840000Y540000D03*
X1820000D03*
X1845545Y516536D03*
X1831330Y517279D03*
X1840000Y580000D03*
X1820000D03*
X1840000Y560000D03*
X1820000D03*
X1862200Y686700D03*
X1856219Y665417D03*
X1850000Y745000D03*
X1837576Y707417D03*
X1820000Y780000D03*
X1857363Y1002625D03*
X1845363D03*
X1849363D03*
X1861363D03*
X1853363D03*
X1856437Y1106400D03*
X1850532Y1153286D03*
X1836231Y1140669D03*
X1860000Y1320000D03*
X1854783Y1369303D03*
X1844783D03*
X1834783D03*
X1824783D03*
X1814783D03*
X1849783D03*
X1859783D03*
X1819783D03*
X1829783D03*
X1839783D03*
X1878030Y5500D03*
X1883030D03*
X1873030D03*
X1868030D03*
X1909030D03*
X1888030D03*
X1880000Y60000D03*
X1900000D03*
X1880000Y80000D03*
X1900000D03*
Y100000D03*
X1880000D03*
X1900000Y120000D03*
X1880000Y140000D03*
Y120000D03*
X1910169Y141870D03*
X1898669Y207992D03*
Y198543D03*
X1903169Y195492D03*
Y180492D03*
Y165492D03*
X1885204Y184345D03*
X1873500Y219000D03*
X1865169Y247161D03*
Y234661D03*
X1903169Y245492D03*
X1898669Y217441D03*
X1903169Y235492D03*
X1881088Y296184D03*
X1903169Y275492D03*
Y265492D03*
X1880969Y276861D03*
X1880000Y340000D03*
Y320000D03*
X1910169Y314114D03*
X1890000Y400000D03*
Y380000D03*
Y360000D03*
Y440000D03*
Y420000D03*
X1910169Y594626D03*
X1903169Y648248D03*
Y633248D03*
Y618248D03*
X1885300Y636800D03*
X1898669Y670197D03*
X1903169Y688248D03*
X1898669Y660748D03*
Y651299D03*
X1903169Y728248D03*
Y718248D03*
Y698248D03*
X1880969Y729617D03*
X1865169Y699917D03*
X1880000Y780000D03*
X1910169Y766870D03*
X1887169Y752917D03*
X1892443Y894350D03*
X1884200Y895000D03*
X1865363Y1002625D03*
X1868100Y1055410D03*
X1903169Y1071004D03*
X1910169Y1047382D03*
X1898669Y1122953D03*
Y1113504D03*
Y1104055D03*
X1903169Y1101004D03*
Y1086004D03*
X1863131Y1133108D03*
X1903169Y1171004D03*
X1903100Y1149700D03*
X1903169Y1141004D03*
X1864352Y1153308D03*
X1871174Y1138730D03*
X1887169Y1205673D03*
X1910169Y1219626D03*
X1903169Y1181004D03*
X1880969Y1182373D03*
X1900000Y1260000D03*
Y1280000D03*
Y1320000D03*
Y1300000D03*
X1904783Y1369303D03*
X1894783D03*
X1884783D03*
X1874783D03*
X1864783D03*
X1899783D03*
X1909783D03*
X1869783D03*
X1879783D03*
X1889783D03*
X1929343Y16525D03*
Y11525D03*
Y6525D03*
X1914030Y5500D03*
X1919030D03*
X1924030D03*
X1920000Y60000D03*
X1929343Y46525D03*
Y41525D03*
Y36525D03*
Y31525D03*
Y26525D03*
Y21525D03*
Y66525D03*
Y61525D03*
Y56525D03*
Y51525D03*
X1920000Y80000D03*
Y100000D03*
X1929343Y116525D03*
Y111525D03*
Y106525D03*
Y101525D03*
Y96525D03*
Y91525D03*
Y86525D03*
Y81525D03*
Y76525D03*
Y71525D03*
X1920000Y120000D03*
X1929343Y121525D03*
Y126525D03*
Y136525D03*
Y146525D03*
Y156525D03*
Y161525D03*
Y151525D03*
Y141525D03*
Y131525D03*
Y176525D03*
Y186525D03*
Y196525D03*
Y206525D03*
Y166525D03*
Y211525D03*
Y201525D03*
Y191525D03*
Y181525D03*
Y171525D03*
Y226525D03*
Y236525D03*
Y246525D03*
Y256525D03*
Y216525D03*
Y261525D03*
Y251525D03*
Y241525D03*
Y231525D03*
Y221525D03*
Y276525D03*
Y286525D03*
Y296525D03*
Y306525D03*
Y266525D03*
Y301525D03*
Y291525D03*
Y281525D03*
Y271525D03*
Y326525D03*
Y336525D03*
Y346525D03*
Y356525D03*
Y316525D03*
Y351525D03*
Y341525D03*
Y331525D03*
Y321525D03*
Y311525D03*
Y376525D03*
Y386525D03*
Y396525D03*
Y406525D03*
Y366525D03*
Y401525D03*
Y391525D03*
Y381525D03*
Y371525D03*
Y361525D03*
Y426525D03*
Y436525D03*
Y446525D03*
Y416525D03*
Y451525D03*
Y441525D03*
Y431525D03*
Y421525D03*
Y411525D03*
Y476525D03*
Y486525D03*
Y496525D03*
Y456525D03*
Y466525D03*
Y501525D03*
Y491525D03*
Y481525D03*
Y471525D03*
Y461525D03*
Y526525D03*
Y536525D03*
Y546525D03*
Y506525D03*
Y516525D03*
Y551525D03*
Y541525D03*
Y531525D03*
Y521525D03*
Y511525D03*
Y576525D03*
Y586525D03*
Y596525D03*
Y556525D03*
Y566525D03*
Y591525D03*
Y581525D03*
Y571525D03*
Y561525D03*
Y626525D03*
Y636525D03*
Y646525D03*
Y606525D03*
Y616525D03*
Y641525D03*
Y631525D03*
Y621525D03*
Y611525D03*
Y601525D03*
Y676525D03*
Y686525D03*
Y696525D03*
Y656525D03*
Y666525D03*
Y691525D03*
Y681525D03*
Y671525D03*
Y661525D03*
Y651525D03*
Y726525D03*
Y736525D03*
Y706525D03*
Y716525D03*
Y741525D03*
Y731525D03*
Y721525D03*
Y711525D03*
Y701525D03*
Y776525D03*
Y786525D03*
Y746525D03*
Y756525D03*
Y766525D03*
Y791525D03*
Y781525D03*
Y771525D03*
Y761525D03*
Y751525D03*
Y826525D03*
Y836525D03*
Y796525D03*
Y806525D03*
Y816525D03*
Y841525D03*
Y831525D03*
Y821525D03*
Y811525D03*
Y801525D03*
Y876525D03*
Y886525D03*
Y846525D03*
Y856525D03*
Y866525D03*
Y881525D03*
Y871525D03*
Y861525D03*
Y851525D03*
Y926525D03*
Y896525D03*
Y906525D03*
Y916525D03*
Y931525D03*
Y921525D03*
Y911525D03*
Y901525D03*
Y891525D03*
Y936525D03*
Y973863D03*
Y978863D03*
Y983863D03*
Y951525D03*
Y956525D03*
Y961525D03*
Y966525D03*
Y946525D03*
Y941525D03*
Y988863D03*
Y993863D03*
Y998863D03*
Y1003863D03*
Y1008863D03*
Y1033863D03*
Y1028863D03*
Y1023863D03*
Y1018863D03*
Y1013863D03*
Y1073863D03*
Y1083863D03*
Y1043863D03*
Y1053863D03*
Y1063863D03*
Y1078863D03*
Y1068863D03*
Y1058863D03*
Y1048863D03*
Y1038863D03*
Y1123863D03*
Y1093863D03*
Y1103863D03*
Y1113863D03*
Y1128863D03*
Y1118863D03*
Y1108863D03*
Y1098863D03*
Y1088863D03*
Y1173863D03*
Y1133863D03*
Y1143863D03*
Y1153863D03*
Y1163863D03*
Y1178863D03*
Y1168863D03*
Y1158863D03*
Y1148863D03*
Y1138863D03*
Y1223863D03*
Y1183863D03*
Y1193863D03*
Y1203863D03*
Y1213863D03*
Y1228863D03*
Y1218863D03*
Y1208863D03*
Y1198863D03*
Y1188863D03*
X1920000Y1260000D03*
X1929343Y1273863D03*
Y1233863D03*
Y1243863D03*
Y1253863D03*
Y1263863D03*
Y1268863D03*
Y1258863D03*
Y1248863D03*
Y1238863D03*
X1920000Y1280000D03*
Y1320000D03*
Y1300000D03*
X1929343Y1323863D03*
Y1283863D03*
Y1293863D03*
Y1303863D03*
Y1313863D03*
Y1318863D03*
Y1308863D03*
Y1298863D03*
Y1288863D03*
Y1278863D03*
Y1333863D03*
Y1343863D03*
Y1353863D03*
X1924783Y1369303D03*
X1914783D03*
X1919783D03*
X1929343Y1358863D03*
Y1348863D03*
Y1338863D03*
Y1328863D03*
Y1363863D03*
G54D28*
X188706Y941328D03*
X194206D03*
X260703Y529168D03*
X255203D03*
X702483Y945989D03*
X730882Y888502D03*
X716233Y868219D03*
X733422Y857828D03*
X721552Y951317D03*
X725852Y951067D03*
X763883Y907689D03*
X755883D03*
X750883Y903689D03*
X802102Y51075D03*
X799102Y48575D03*
X802102Y46075D03*
X799102Y43575D03*
X802102Y41075D03*
X868100Y685600D03*
X871700D03*
X875300D03*
X884600Y688800D03*
X881000D03*
X877400D03*
X891000Y743500D03*
X870500Y762500D03*
X932294Y1379995D03*
X928194D03*
X1843731Y936066D03*
X1843811Y940067D03*
X1830665Y941751D03*
X1836165D03*
X1908107Y831894D03*
X1902607D03*
X1907999Y846368D03*
X1902499D03*
G54D23*
X111800Y987200D03*
Y983200D03*
X115800Y979200D03*
X119800Y971200D03*
Y975200D03*
Y979200D03*
X115800Y975200D03*
X119800Y987200D03*
Y983200D03*
X115800Y971200D03*
Y983200D03*
Y987200D03*
X119163Y959625D03*
X121914Y1003491D03*
X153263Y568725D03*
X146263D03*
X144263Y573225D03*
X138763Y568725D03*
X148763Y576225D03*
X188614Y591491D03*
X182500Y559200D03*
Y571200D03*
Y575200D03*
X178500D03*
Y571200D03*
X182500Y567200D03*
X186500Y559200D03*
Y563200D03*
Y567200D03*
X182500Y563200D03*
X186500Y575200D03*
Y571200D03*
X184017Y951112D03*
Y945612D03*
X198463Y945525D03*
Y951025D03*
X265392Y539225D03*
Y533725D03*
X250586Y533920D03*
Y539420D03*
X465346Y1122953D03*
X858632Y399200D03*
X855032D03*
Y395600D03*
X858632D03*
X855032Y392000D03*
X858632D03*
X852832Y406400D03*
Y402800D03*
X856432Y406400D03*
Y402800D03*
X852832Y410000D03*
X856432D03*
X1398493Y314114D03*
X1717681Y1006054D03*
X1712181Y1001554D03*
X1757600Y987200D03*
X1761600D03*
Y983200D03*
X1757600D03*
X1761600Y991200D03*
Y999200D03*
Y995200D03*
X1757600Y991200D03*
X1753600Y995200D03*
Y999200D03*
X1757600D03*
Y995200D03*
X1726681Y1001554D03*
X1719681D03*
X1722181Y1009054D03*
X1763714Y1015491D03*
X1840419Y945557D03*
Y951057D03*
X1825945Y945449D03*
Y950949D03*
G54D37*
X944882Y-63877D03*
G54D39*
X942126Y58465D03*
Y346457D03*
Y437598D03*
Y725590D03*
X1110236Y58465D03*
Y346457D03*
Y437598D03*
Y725590D03*
G54D34*
X496653Y80906D03*
X1465157D03*
G54D15*
X60540Y-85109D03*
X59536Y1573374D03*
X79000Y1301900D03*
X1826700Y77600D03*
X1865705Y1573374D03*
X1898432Y-93682D03*
X1908500Y1346800D03*
G54D12*
X15157Y474409D03*
X904921Y-25591D03*
X1894684Y474409D03*
G54D18*
X80019Y51968D03*
X127263Y20472D03*
X631200Y51968D03*
X678444Y20472D03*
X1250689Y51969D03*
X1297933Y20472D03*
X1801870Y51969D03*
X1849114Y20472D03*
G54D10*
X15157Y21653D03*
X904921Y564960D03*
X1894685Y21654D03*
G54D35*
X496653Y110552D03*
X1465157D03*
G54D26*
X173228Y1062992D03*
X421653Y1141732D03*
X670079Y1062992D03*
X1343701D03*
X1592126Y1141732D03*
X1840551Y1062992D03*
G54D36*
X503248Y829921D03*
X1673917D03*
G54D13*
X31496Y882677D03*
X168307Y646457D03*
X660236D03*
X718110Y820866D03*
X1366142Y646457D03*
X1462992Y866929D03*
X1602756Y646457D03*
X1903346Y803937D03*
G54D40*
X975787Y-25590D03*
G54D17*
X103642Y36220D03*
X654822D03*
X1274311D03*
X1825492D03*
G54D27*
X173228Y1114173D03*
X670079D03*
X1343700D03*
X1840551D03*
G54D41*
X975786Y564960D03*
G54D45*
X1104527Y1630792D03*
G54D16*
X47000Y1107500D03*
X557279Y570331D03*
X602379Y547831D03*
X570779Y542831D03*
X568779Y512831D03*
X575779D03*
X571408Y577450D03*
X584279Y577431D03*
X575779D03*
X579718D03*
X592779D03*
X588779D03*
X562279D03*
X567641Y577473D03*
X615119Y551586D03*
X615147Y565956D03*
X704399Y626799D03*
Y618399D03*
Y622599D03*
X748500Y1287500D03*
X752000Y1197500D03*
X756000Y1225500D03*
X770000Y1231500D03*
X769500Y1283500D03*
X827000Y1168000D03*
X802500Y1194500D03*
X807500D03*
X812500D03*
X810000Y1191500D03*
X805000D03*
X870163Y836153D03*
X865663Y834403D03*
X895869Y932822D03*
X898920Y1020000D03*
X906000Y1222000D03*
X924500Y1236000D03*
X938000Y1499200D03*
X941000Y1564200D03*
X937000D03*
X926500Y1556700D03*
X931500Y1564200D03*
X913250Y1547700D03*
X940000Y1529200D03*
X962900Y905000D03*
X953967Y933635D03*
X948942Y974655D03*
X961134Y976191D03*
X946138Y1006299D03*
X953500Y1563200D03*
X962000Y1564200D03*
X958000D03*
X949000D03*
X945000D03*
X972001Y1533926D03*
X986614Y1619764D03*
X974016D03*
Y1597126D03*
X986614D03*
X974016Y1591220D03*
Y1603031D03*
Y1613858D03*
X986614Y1591220D03*
Y1613858D03*
Y1603031D03*
X974016Y1625669D03*
X986614D03*
X1031563Y852453D03*
X1025774Y1001538D03*
X992994Y1005740D03*
X1037000Y1067100D03*
X1032500D03*
X1017000Y1093950D03*
X1021200Y1094300D03*
X1002362Y1597126D03*
X1014961D03*
X1030709D03*
X1002362Y1591220D03*
Y1603031D03*
X1014961Y1591220D03*
Y1603031D03*
X1030709Y1591220D03*
Y1603031D03*
X1076000Y-10500D03*
X1062854Y83434D03*
X1053200Y901703D03*
X1043882Y901568D03*
X1082500Y1067100D03*
X1073500D03*
X1064500Y1096150D03*
X1068700Y1096600D03*
X1066750Y1224035D03*
X1079250D03*
X1066750Y1209862D03*
X1079250D03*
X1066750Y1216949D03*
X1079250D03*
X1066750Y1231122D03*
X1079250D03*
X1066750Y1238209D03*
X1079250D03*
X1066750Y1245295D03*
X1079250D03*
X1066750Y1301988D03*
X1079250D03*
X1066750Y1309075D03*
X1079250D03*
X1066750Y1316161D03*
X1079250D03*
X1066750Y1323248D03*
X1079250D03*
X1066750Y1294902D03*
X1079250D03*
X1066750Y1330335D03*
X1079250D03*
X1066750Y1387028D03*
X1079250D03*
X1066750Y1394114D03*
X1079250D03*
X1066750Y1401201D03*
X1079250D03*
X1066750Y1408287D03*
X1079250D03*
X1066750Y1415374D03*
X1079250D03*
X1066750Y1379941D03*
X1079250D03*
X1043307Y1597126D03*
Y1591220D03*
Y1603031D03*
X1100847Y905617D03*
X1105847D03*
X1110847D03*
X1108347Y902617D03*
X1103347D03*
X1119700Y1067200D03*
X1124500D03*
X1101580Y1091120D03*
X1107100Y1096050D03*
X1111600Y1097800D03*
X1090818Y1531620D03*
X1092927Y1558887D03*
Y1555087D03*
X1095938Y1531620D03*
Y1535420D03*
X1090818D03*
X1096547Y1558887D03*
Y1555087D03*
X1265250Y167823D03*
X1252750D03*
X1376963D03*
X1355700Y587600D03*
X1359700D03*
X1389463Y167823D03*
G54D25*
X127988Y194242D03*
Y181742D03*
Y634498D03*
Y646998D03*
Y1087254D03*
Y1099754D03*
X252200Y194242D03*
Y181742D03*
Y634498D03*
Y646998D03*
Y1087254D03*
Y1099754D03*
X322545Y72845D03*
X376413Y194242D03*
Y181742D03*
Y634498D03*
Y646998D03*
Y1087254D03*
Y1099754D03*
X453473Y1089300D03*
X500625Y194242D03*
Y181742D03*
Y634498D03*
Y646998D03*
X460673Y1071976D03*
X460873Y1077526D03*
X500625Y1087254D03*
Y1099754D03*
X624838Y194242D03*
Y181742D03*
Y634498D03*
Y646998D03*
Y1087254D03*
Y1099754D03*
X696787Y580633D03*
X749051Y194242D03*
Y181742D03*
Y634498D03*
Y646998D03*
X708683Y876958D03*
X749051Y1087254D03*
Y1099754D03*
X928600Y-115200D03*
X986713Y-115570D03*
X971713D03*
X1046713D03*
X1076713D03*
X1117535Y-115157D03*
X1091089Y988592D03*
X1105262D03*
X1119435D03*
X1133609D03*
X1095026Y995678D03*
X1109199D03*
X1123372D03*
X1091089Y1002765D03*
X1105262D03*
X1119435D03*
X1133609D03*
X1095026Y1009852D03*
X1109199D03*
X1123372D03*
X1091089Y1016938D03*
X1105262D03*
X1119435D03*
X1133609D03*
X1095026Y1024025D03*
X1109199D03*
X1123372D03*
X1091089Y1031111D03*
X1105262D03*
X1119435D03*
X1133609D03*
X1095026Y1038198D03*
X1109199D03*
X1123372D03*
X1091089Y1160257D03*
Y1174430D03*
X1105262Y1160257D03*
Y1174430D03*
X1119435Y1160257D03*
Y1174430D03*
X1133609Y1160257D03*
Y1174430D03*
X1095026Y1167343D03*
X1109199D03*
X1123372D03*
X1091089Y1188603D03*
Y1202776D03*
Y1216949D03*
X1105262Y1188603D03*
Y1202776D03*
Y1216949D03*
X1119435Y1188603D03*
Y1202776D03*
Y1216949D03*
X1133609Y1188603D03*
Y1202776D03*
Y1216949D03*
X1095026Y1181516D03*
Y1195690D03*
Y1209863D03*
Y1224036D03*
X1109199Y1181516D03*
Y1195690D03*
Y1209863D03*
Y1224036D03*
X1123372Y1181516D03*
Y1195690D03*
Y1209863D03*
Y1224036D03*
X1091089Y1231123D03*
Y1245296D03*
Y1259469D03*
Y1273642D03*
X1105262Y1231123D03*
Y1245296D03*
Y1259469D03*
Y1273642D03*
X1119435Y1231123D03*
Y1245296D03*
Y1259469D03*
Y1273642D03*
X1133609Y1231123D03*
Y1245296D03*
Y1259469D03*
Y1273642D03*
X1095026Y1238209D03*
Y1252382D03*
Y1266556D03*
X1109199Y1238209D03*
Y1252382D03*
Y1266556D03*
X1123372Y1238209D03*
Y1252382D03*
Y1266556D03*
X1091089Y1287816D03*
Y1301989D03*
Y1316162D03*
X1105262Y1287816D03*
Y1301989D03*
Y1316162D03*
X1119435Y1287816D03*
Y1301989D03*
Y1316162D03*
X1133609Y1287816D03*
Y1301989D03*
Y1316162D03*
X1095026Y1280729D03*
Y1294902D03*
Y1309075D03*
Y1323249D03*
X1109199Y1280729D03*
Y1294902D03*
Y1309075D03*
Y1323249D03*
X1123372Y1280729D03*
Y1294902D03*
Y1309075D03*
Y1323249D03*
X1091089Y1330335D03*
Y1344508D03*
Y1358682D03*
Y1372855D03*
X1105262Y1330335D03*
Y1344508D03*
Y1358682D03*
Y1372855D03*
X1119435Y1330335D03*
Y1344508D03*
Y1358682D03*
Y1372855D03*
X1133609Y1330335D03*
Y1344508D03*
Y1358682D03*
Y1372855D03*
X1095026Y1337422D03*
Y1351595D03*
Y1365768D03*
X1109199Y1337422D03*
Y1351595D03*
Y1365768D03*
X1123372Y1337422D03*
Y1351595D03*
Y1365768D03*
X1091089Y1387028D03*
Y1401201D03*
X1105262Y1387028D03*
Y1401201D03*
X1119435Y1387028D03*
Y1401201D03*
X1133609Y1387028D03*
Y1401201D03*
X1095026Y1379942D03*
Y1394115D03*
Y1408288D03*
X1109199Y1379942D03*
Y1394115D03*
Y1408288D03*
X1123372Y1379942D03*
Y1394115D03*
Y1408288D03*
X1101457Y1588583D03*
X1119685D03*
X1108150D03*
X1126378D03*
X1182590Y254388D03*
X1174037Y281343D03*
X1278500Y634498D03*
Y646998D03*
Y1087254D03*
Y1099754D03*
X1402713Y181742D03*
Y194242D03*
Y634498D03*
Y646998D03*
Y1087254D03*
Y1099754D03*
X1526925Y181742D03*
Y194242D03*
Y634498D03*
Y646998D03*
Y1087254D03*
Y1099754D03*
X1651138Y181742D03*
Y194242D03*
Y634498D03*
Y646998D03*
Y1087254D03*
Y1099754D03*
X1725350Y634498D03*
Y646998D03*
X1775350Y181742D03*
Y194242D03*
Y1087254D03*
Y1099754D03*
X1859017Y161725D03*
X1859117Y167375D03*
X1851717Y179075D03*
X1858917Y614481D03*
X1859117Y620131D03*
X1851717Y635331D03*
X1848491Y819787D03*
Y823787D03*
Y815787D03*
Y807787D03*
Y811787D03*
X1899563Y181742D03*
Y194242D03*
Y634498D03*
Y646998D03*
X1871000Y1073300D03*
X1899563Y1087254D03*
Y1099754D03*
X1863700Y1085000D03*
G54D29*
X184295Y1009469D03*
Y1014969D03*
X198741Y1014882D03*
Y1009382D03*
X265275Y596896D03*
X250974Y597308D03*
X265275Y602396D03*
X250974Y602808D03*
X429724Y63977D03*
X443898D03*
X458071D03*
X436811Y67914D03*
X450984D03*
X429724Y92323D03*
Y106496D03*
Y78150D03*
X436811Y82087D03*
X450984D03*
X443898Y92323D03*
X458071D03*
X436811Y96260D03*
X450984D03*
X443898Y106496D03*
X458071D03*
X436811Y110433D03*
X450984D03*
X443898Y78150D03*
X458071D03*
X429724Y120670D03*
X443898D03*
X458071D03*
X465157Y67914D03*
X472244Y63977D03*
X479331Y67914D03*
X465157Y82087D03*
Y96260D03*
Y110433D03*
X479331Y82087D03*
X472244Y92323D03*
X479331Y96260D03*
X472244Y106496D03*
X479331Y110433D03*
X472244Y78150D03*
Y120670D03*
X514764Y63977D03*
X550197Y67914D03*
X536024D03*
X521850D03*
X543110Y63977D03*
X528937D03*
X557283D03*
X514764Y106496D03*
Y92323D03*
Y78150D03*
X550197Y110433D03*
X536024D03*
X521850D03*
X543110Y106496D03*
X528937D03*
X550197Y96260D03*
X536024D03*
X521850D03*
X543110Y92323D03*
X528937D03*
X550197Y82087D03*
X536024D03*
X521850D03*
X543110Y78150D03*
X528937D03*
X557283Y106496D03*
Y92323D03*
Y78150D03*
X514764Y120670D03*
X543110D03*
X528937D03*
X557283D03*
X564370Y67914D03*
Y110433D03*
Y96260D03*
Y82087D03*
X1398228Y63977D03*
X1412402D03*
X1426575D03*
X1405315Y67914D03*
X1419488D03*
X1398228Y92323D03*
Y106496D03*
Y78150D03*
X1405315Y82087D03*
X1419488D03*
X1412402Y92323D03*
X1426575D03*
X1405315Y96260D03*
X1419488D03*
X1412402Y106496D03*
X1426575D03*
X1405315Y110433D03*
X1419488D03*
X1412402Y78150D03*
X1426575D03*
X1398228Y120670D03*
X1412402D03*
X1426575D03*
X1433661Y67914D03*
X1440748Y63977D03*
X1447835Y67914D03*
X1433661Y82087D03*
Y96260D03*
Y110433D03*
X1447835Y82087D03*
X1440748Y92323D03*
X1447835Y96260D03*
X1440748Y106496D03*
X1447835Y110433D03*
X1440748Y78150D03*
Y120670D03*
X1483268Y63977D03*
X1518701Y67914D03*
X1504528D03*
X1490354D03*
X1511614Y63977D03*
X1497441D03*
X1483268Y106496D03*
Y92323D03*
Y78150D03*
X1518701Y110433D03*
X1504528D03*
X1490354D03*
X1511614Y106496D03*
X1497441D03*
X1518701Y96260D03*
X1504528D03*
X1490354D03*
X1511614Y92323D03*
X1497441D03*
X1518701Y82087D03*
X1504528D03*
X1490354D03*
X1511614Y78150D03*
X1497441D03*
X1483268Y120670D03*
X1511614D03*
X1497441D03*
X1532874Y67914D03*
X1525787Y63977D03*
X1532874Y110433D03*
X1525787Y106496D03*
X1532874Y96260D03*
X1525787Y92323D03*
X1532874Y82087D03*
X1525787Y78150D03*
Y120670D03*
X1825971Y1015512D03*
Y1010012D03*
X1840445Y1015620D03*
Y1010120D03*
X1912551Y836444D03*
Y841944D03*
G54D30*
X188552Y1019166D03*
X194052D03*
X255410Y607833D03*
X260910D03*
X1850151Y835119D03*
X1850177Y838746D03*
X1838239Y831626D03*
X1845579Y831731D03*
X1838311Y827911D03*
X1845651Y828016D03*
X1860276Y916059D03*
Y912059D03*
X1835895Y1020064D03*
X1830395D03*
X1872276Y916059D03*
X1876276D03*
Y920059D03*
X1872276D03*
X1868276Y916059D03*
X1864276Y912059D03*
X1868276D03*
X1864276Y916059D03*
X1876276Y912059D03*
X1872276D03*
X1875801Y946796D03*
X1875769Y951122D03*
X1880122Y954062D03*
X1880383Y950341D03*
G36*
G01X149668Y380135D02*
G02X112735I-18466J-14781D01*
G03X119308Y392599I-29176J23351D01*
G02X143095I11894J-3623D01*
G03X149668Y380135I35749J10887D01*
G37*
G36*
G01X149667Y832891D02*
G02X112734I-18466J-14781D01*
G03X119307Y845355I-29176J23351D01*
G02X143094I11894J-3623D01*
G03X149667Y832891I35749J10887D01*
G37*
G36*
G01X149668Y1285647D02*
G02X112735I-18466J-14781D01*
G03X119308Y1298111I-29176J23351D01*
G02X143095I11894J-3623D01*
G03X149668Y1285647I35749J10887D01*
G37*
G36*
G01X397699Y380135D02*
G02X360766I-18467J-14781D01*
G03X367339Y392599I-29176J23351D01*
G02X391126I11894J-3623D01*
G03X397699Y380135I35749J10887D01*
G37*
G36*
G01Y832891D02*
G02X360766I-18467J-14781D01*
G03X367339Y845355I-29176J23351D01*
G02X391126I11894J-3623D01*
G03X397699Y832891I35749J10887D01*
G37*
G36*
G01Y1285647D02*
G02X360766I-18467J-14781D01*
G03X367339Y1298111I-29176J23351D01*
G02X391126I11894J-3623D01*
G03X397699Y1285647I35749J10887D01*
G37*
G36*
G01X645730Y380135D02*
G02X608797I-18466J-14781D01*
G03X615370Y392599I-29176J23351D01*
G02X639157I11893J-3623D01*
G03X645730Y380135I35749J10887D01*
G37*
G36*
G01Y832891D02*
G02X608797I-18466J-14781D01*
G03X615370Y845355I-29176J23351D01*
G02X639157I11893J-3623D01*
G03X645730Y832891I35749J10887D01*
G37*
G36*
G01Y1285647D02*
G02X608797I-18466J-14781D01*
G03X615370Y1298111I-29176J23351D01*
G02X639157I11893J-3623D01*
G03X645730Y1285647I35749J10887D01*
G37*
G36*
G01X814924Y265984D02*
G02X777991I-18467J-14781D01*
G03X784564Y278448I-29176J23351D01*
G02X808351I11893J-3623D01*
G03X814924Y265984I35749J10887D01*
G37*
G36*
G01Y738425D02*
G02X777991I-18467J-14781D01*
G03X784564Y750889I-29176J23351D01*
G02X808351I11893J-3623D01*
G03X814924Y738425I35749J10887D01*
G37*
G36*
G01X979885Y1090394D02*
G02X942952I-18467J-14781D01*
G03X949525Y1102858I-29176J23351D01*
G02X973312I11894J-3623D01*
G03X979885Y1090394I35749J10887D01*
G37*
G36*
G01Y1432913D02*
G02X942952I-18467J-14781D01*
G03X949525Y1445377I-29176J23351D01*
G02X973312I11894J-3623D01*
G03X979885Y1432913I35749J10887D01*
G37*
G36*
G01X1200357Y558898D02*
G02X1163424I-18467J-14781D01*
G03X1169997Y571362I-29176J23351D01*
G02X1193784I11894J-3623D01*
G03X1200357Y558898I35749J10887D01*
G37*
G36*
G01X1200337Y972261D02*
G02X1163404I-18467J-14781D01*
G03X1169977Y984725I-29176J23351D01*
G02X1193764I11894J-3623D01*
G03X1200337Y972261I35749J10887D01*
G37*
G36*
G01X1200357Y1562835D02*
G02X1163424I-18467J-14781D01*
G03X1169997Y1575299I-29176J23351D01*
G02X1193784I11894J-3623D01*
G03X1200357Y1562835I35749J10887D01*
G37*
G36*
G01X1320337Y380135D02*
G02X1283404I-18467J-14781D01*
G03X1289977Y392599I-29176J23351D01*
G02X1313764I11894J-3623D01*
G03X1320337Y380135I35749J10887D01*
G37*
G36*
G01Y832891D02*
G02X1283404I-18467J-14781D01*
G03X1289977Y845355I-29176J23351D01*
G02X1313764I11894J-3623D01*
G03X1320337Y832891I35749J10887D01*
G37*
G36*
G01Y1285647D02*
G02X1283404I-18467J-14781D01*
G03X1289977Y1298111I-29176J23351D01*
G02X1313764I11894J-3623D01*
G03X1320337Y1285647I35749J10887D01*
G37*
G36*
G01X1568368Y380135D02*
G02X1531435I-18467J-14781D01*
G03X1538008Y392599I-29176J23351D01*
G02X1561795I11894J-3623D01*
G03X1568368Y380135I35749J10887D01*
G37*
G36*
G01Y832891D02*
G02X1531435I-18467J-14781D01*
G03X1538008Y845355I-29176J23351D01*
G02X1561795I11894J-3623D01*
G03X1568368Y832891I35749J10887D01*
G37*
G36*
G01Y1285647D02*
G02X1531435I-18467J-14781D01*
G03X1538008Y1298111I-29176J23351D01*
G02X1561795I11894J-3623D01*
G03X1568368Y1285647I35749J10887D01*
G37*
G36*
G01X1816400Y380135D02*
G02X1779467I-18466J-14781D01*
G03X1786040Y392599I-29176J23351D01*
G02X1809827I11894J-3623D01*
G03X1816400Y380135I35749J10887D01*
G37*
G36*
G01Y832891D02*
G02X1779467I-18466J-14781D01*
G03X1786040Y845355I-29176J23351D01*
G02X1809827I11894J-3623D01*
G03X1816400Y832891I35749J10887D01*
G37*
G36*
G01Y1285647D02*
G02X1779467I-18466J-14781D01*
G03X1786040Y1298111I-29176J23351D01*
G02X1809827I11894J-3623D01*
G03X1816400Y1285647I35749J10887D01*
G37*
%LPC*%
G75*
G54D46*
G01X363248Y-425196D02*
Y-505196D01*
G01D02*
X1639148D01*
G01X359248Y-409196D02*
G02I-12000J0D01*
G01X354098D02*
G02I-6850J0D01*
G01X347248Y-425196D02*
Y-393196D01*
G01X363248Y-425196D02*
X1639148D01*
G01X363248Y-460696D02*
X1639148D01*
G01X363248Y-409196D02*
X331248D01*
G01X720748Y-425196D02*
Y-505196D01*
G01X858248Y-425196D02*
Y-505196D01*
G01X973248Y-425196D02*
Y-505196D01*
G01X1271648Y-425196D02*
Y-505196D01*
G01X1441648Y-425196D02*
Y-505196D01*
G01X1639148Y-425196D02*
Y-505196D01*
G01X1667148Y-409196D02*
G02I-12000J0D01*
G01X1661998D02*
G02I-6850J0D01*
G01X1655148Y-425196D02*
Y-393196D01*
G01X1671148Y-409196D02*
X1639148D01*
G54D47*
G01X394744Y-485863D02*
X395618Y-484988D01*
X396273Y-483530D01*
X396710Y-481487D01*
X396273Y-479738D01*
X395400Y-478571D01*
X393871Y-477696D01*
X387976D01*
Y-495196D01*
X395181D01*
X396710Y-494030D01*
X397583Y-492279D01*
X398020Y-490238D01*
X397583Y-488196D01*
X396273Y-486446D01*
X394744Y-485863D01*
X387976D01*
G01X407441Y-495196D02*
Y-483530D01*
G01Y-485863D02*
X408533Y-484696D01*
X409625Y-483821D01*
X411153Y-483530D01*
X412244Y-483821D01*
X413555Y-484696D01*
G01X423413Y-500446D02*
X424723Y-501029D01*
X426470Y-500446D01*
X427561Y-499280D01*
X428435Y-497821D01*
X429744Y-493155D01*
X432583Y-483530D01*
G01X425596D02*
X429744Y-493155D01*
G01X448991Y-484988D02*
X447463Y-483821D01*
X446153Y-483530D01*
X444406Y-484113D01*
X443096Y-485279D01*
X442223Y-487321D01*
X442004Y-489363D01*
X442223Y-491405D01*
X443096Y-493155D01*
X444406Y-494613D01*
X446153Y-495196D01*
X447681Y-494613D01*
X448991Y-493446D01*
G01X459723Y-487321D02*
X466710D01*
X466055Y-485279D01*
X464963Y-484113D01*
X463435Y-483530D01*
X461906Y-483821D01*
X460596Y-484696D01*
X459723Y-486738D01*
X459286Y-488488D01*
Y-490238D01*
X459723Y-491988D01*
X460815Y-493738D01*
X462125Y-494904D01*
X463653Y-495196D01*
X465181Y-494613D01*
X466710Y-492863D01*
G01X502801Y-479155D02*
X501491Y-478279D01*
X499963Y-477696D01*
X498216D01*
X496251Y-478571D01*
X494723Y-480029D01*
X493631Y-481780D01*
X492758Y-484696D01*
X492539Y-487321D01*
X492976Y-489946D01*
X493631Y-491696D01*
X494941Y-493446D01*
X496470Y-494613D01*
X497998Y-495196D01*
X499526D01*
X501055Y-494613D01*
X502365Y-493738D01*
X503457Y-492572D01*
G01X519428Y-495196D02*
Y-483530D01*
G01Y-485571D02*
X518555Y-484405D01*
X517244Y-483821D01*
X515716Y-483530D01*
X514188Y-484113D01*
X512878Y-485279D01*
X512004Y-487029D01*
X511568Y-489363D01*
X512004Y-491696D01*
X512878Y-493446D01*
X514188Y-494613D01*
X515716Y-495196D01*
X517244Y-494904D01*
X518555Y-494030D01*
X519428Y-492863D01*
G01X529286Y-495196D02*
Y-483530D01*
G01Y-486446D02*
X530160Y-484988D01*
X531470Y-483821D01*
X533216Y-483530D01*
X534744Y-483821D01*
X536055Y-484988D01*
X536710Y-487029D01*
Y-495196D01*
G01X545913Y-500446D02*
X547223Y-501029D01*
X548970Y-500446D01*
X550061Y-499280D01*
X550935Y-497821D01*
X552244Y-493155D01*
X555083Y-483530D01*
G01X548096D02*
X552244Y-493155D01*
G01X567998Y-495196D02*
X566688Y-494904D01*
X565378Y-493738D01*
X564504Y-491696D01*
X564068Y-489363D01*
X564504Y-487029D01*
X565378Y-484988D01*
X566688Y-483821D01*
X567998Y-483530D01*
X569308Y-483821D01*
X570618Y-484988D01*
X571491Y-487029D01*
X571710Y-489363D01*
X571491Y-491696D01*
X570618Y-493738D01*
X569308Y-494904D01*
X567998Y-495196D01*
G01X581786D02*
Y-483530D01*
G01Y-486446D02*
X582660Y-484988D01*
X583970Y-483821D01*
X585716Y-483530D01*
X587244Y-483821D01*
X588555Y-484988D01*
X589210Y-487029D01*
Y-495196D01*
G01X616350D02*
Y-477696D01*
X624646D01*
G01X621590Y-486154D02*
X616350D01*
G01X637998Y-495779D02*
X637561Y-495488D01*
Y-494904D01*
X637998Y-494613D01*
X638435Y-494904D01*
Y-495488D01*
X637998Y-495779D01*
G01X650695Y-495196D02*
Y-477696D01*
X655061D01*
X656808Y-478571D01*
X658118Y-479738D01*
X659210Y-481487D01*
X660083Y-483530D01*
X660301Y-486446D01*
X660083Y-489363D01*
X659210Y-491405D01*
X658118Y-493155D01*
X656808Y-494321D01*
X655061Y-495196D01*
X650695D01*
G01X668631D02*
Y-477696D01*
X673871D01*
X675618Y-478571D01*
X676928Y-480613D01*
X677365Y-482946D01*
X676928Y-485279D01*
X675836Y-487029D01*
X673871Y-487905D01*
X668631D01*
G01X692244Y-485863D02*
X693118Y-484988D01*
X693773Y-483530D01*
X694210Y-481487D01*
X693773Y-479738D01*
X692900Y-478571D01*
X691371Y-477696D01*
X685476D01*
Y-495196D01*
X692681D01*
X694210Y-494030D01*
X695083Y-492279D01*
X695520Y-490238D01*
X695083Y-488196D01*
X693773Y-486446D01*
X692244Y-485863D01*
X685476D01*
G01X501071Y-450196D02*
Y-432696D01*
X506748Y-447279D01*
X512425Y-432696D01*
Y-450196D01*
G01X524248D02*
X522938Y-449904D01*
X521628Y-448738D01*
X520754Y-446696D01*
X520318Y-444363D01*
X520754Y-442029D01*
X521628Y-439988D01*
X522938Y-438821D01*
X524248Y-438530D01*
X525558Y-438821D01*
X526868Y-439988D01*
X527741Y-442029D01*
X527960Y-444363D01*
X527741Y-446696D01*
X526868Y-448738D01*
X525558Y-449904D01*
X524248Y-450196D01*
G01X545678Y-432696D02*
Y-450196D01*
G01Y-447572D02*
X544805Y-449030D01*
X543494Y-449904D01*
X541966Y-450196D01*
X540220Y-449613D01*
X538910Y-448155D01*
X538036Y-446405D01*
X537818Y-444363D01*
X538036Y-442321D01*
X538910Y-440571D01*
X540220Y-439113D01*
X541966Y-438530D01*
X543494Y-438821D01*
X544586Y-439405D01*
X545678Y-440571D01*
G01X555973Y-442321D02*
X562960D01*
X562305Y-440279D01*
X561213Y-439113D01*
X559685Y-438530D01*
X558156Y-438821D01*
X556846Y-439696D01*
X555973Y-441738D01*
X555536Y-443488D01*
Y-445238D01*
X555973Y-446988D01*
X557065Y-448738D01*
X558375Y-449904D01*
X559903Y-450196D01*
X561431Y-449613D01*
X562960Y-447863D01*
G01X576748Y-450196D02*
Y-432696D01*
G01X754448Y-495196D02*
Y-477696D01*
X751828Y-481196D01*
G01Y-495196D02*
X757068D01*
G01X767800Y-487905D02*
X769328Y-485863D01*
X770638Y-484696D01*
X772385Y-484113D01*
X773913Y-484696D01*
X775005Y-485863D01*
X775878Y-487613D01*
X776096Y-489654D01*
X775878Y-491405D01*
X775005Y-493155D01*
X773694Y-494613D01*
X772166Y-495196D01*
X770420Y-494613D01*
X768891Y-492863D01*
X768018Y-490238D01*
X767800Y-487321D01*
X768236Y-483530D01*
X768891Y-481487D01*
X769983Y-479446D01*
X771511Y-477988D01*
X773040Y-477696D01*
X774568Y-478279D01*
X775660Y-479738D01*
G01X784645Y-491696D02*
X785954Y-493738D01*
X787701Y-494904D01*
X789666Y-495196D01*
X791413Y-494904D01*
X793160Y-493446D01*
X794251Y-491696D01*
X794470Y-489946D01*
X794033Y-487905D01*
X792505Y-486446D01*
X790976Y-485863D01*
X789011D01*
G01X790976D02*
X792286Y-484988D01*
X793378Y-483530D01*
X793815Y-481780D01*
X793378Y-480029D01*
X792286Y-478571D01*
X790321Y-477696D01*
X788356Y-477988D01*
X786391Y-479155D01*
G01X806948Y-495196D02*
Y-477696D01*
X804328Y-481196D01*
G01Y-495196D02*
X809568D01*
G01X819645Y-492572D02*
X820954Y-494030D01*
X822483Y-494904D01*
X824448Y-495196D01*
X826413Y-494613D01*
X827941Y-493446D01*
X829033Y-491405D01*
X829251Y-489071D01*
X828815Y-486738D01*
X827723Y-485279D01*
X826194Y-484113D01*
X824666Y-483821D01*
X823138Y-484113D01*
X821173Y-485279D01*
X821828Y-477696D01*
X827723D01*
G01X741331Y-450196D02*
Y-432696D01*
X746571D01*
X748318Y-433571D01*
X749628Y-435613D01*
X750065Y-437946D01*
X749628Y-440279D01*
X748536Y-442029D01*
X746571Y-442905D01*
X741331D01*
G01X768001Y-434155D02*
X766691Y-433279D01*
X765163Y-432696D01*
X763416D01*
X761451Y-433571D01*
X759923Y-435029D01*
X758831Y-436780D01*
X757958Y-439696D01*
X757739Y-442321D01*
X758176Y-444946D01*
X758831Y-446696D01*
X760141Y-448446D01*
X761670Y-449613D01*
X763198Y-450196D01*
X764726D01*
X766255Y-449613D01*
X767565Y-448738D01*
X768657Y-447572D01*
G01X782444Y-440863D02*
X783318Y-439988D01*
X783973Y-438530D01*
X784410Y-436487D01*
X783973Y-434738D01*
X783100Y-433571D01*
X781571Y-432696D01*
X775676D01*
Y-450196D01*
X782881D01*
X784410Y-449030D01*
X785283Y-447279D01*
X785720Y-445238D01*
X785283Y-443196D01*
X783973Y-441446D01*
X782444Y-440863D01*
X775676D01*
G01X791648Y-456029D02*
X804748D01*
G01X810676Y-450196D02*
Y-432696D01*
X820720Y-450196D01*
Y-432696D01*
G01X833198Y-450196D02*
X831451Y-449904D01*
X829923Y-448738D01*
X828613Y-446988D01*
X827739Y-444946D01*
X827303Y-442613D01*
Y-440279D01*
X827739Y-437946D01*
X828613Y-435904D01*
X829923Y-434155D01*
X831451Y-432988D01*
X833198Y-432696D01*
X834944Y-432988D01*
X836473Y-434155D01*
X837783Y-435904D01*
X838657Y-437946D01*
X839093Y-440279D01*
Y-442613D01*
X838657Y-444946D01*
X837783Y-446988D01*
X836473Y-448738D01*
X834944Y-449904D01*
X833198Y-450196D01*
G01X884039Y-432696D02*
X889498Y-450196D01*
X894957Y-432696D01*
G01X911365Y-450196D02*
X902631D01*
Y-432696D01*
X911365D01*
G01X907871Y-441154D02*
X902631D01*
G01X920131Y-450196D02*
Y-432696D01*
X925590D01*
X927336Y-433571D01*
X928428Y-434738D01*
X928865Y-437071D01*
X928428Y-439405D01*
X927118Y-440863D01*
X925590Y-441738D01*
X920131D01*
G01X925590D02*
X928865Y-450196D01*
G01X941998Y-450779D02*
X941561Y-450488D01*
Y-449904D01*
X941998Y-449613D01*
X942435Y-449904D01*
Y-450488D01*
X941998Y-450779D01*
G01X915748Y-495196D02*
Y-477696D01*
X913128Y-481196D01*
G01Y-495196D02*
X918368D01*
G01X1082981Y-477696D02*
Y-495196D01*
X1091715D01*
G01X1100700Y-480613D02*
X1102010Y-478863D01*
X1103538Y-477988D01*
X1105285Y-477696D01*
X1107468Y-478279D01*
X1108996Y-479738D01*
X1109433Y-481487D01*
X1109215Y-483238D01*
X1108341Y-484696D01*
X1103975Y-487613D01*
X1102010Y-489654D01*
X1100700Y-492572D01*
X1100263Y-495196D01*
X1109433D01*
G01X1123658Y-486446D02*
X1128025D01*
Y-491696D01*
X1126715Y-493446D01*
X1125186Y-494613D01*
X1123003Y-495196D01*
X1120820Y-494613D01*
X1119291Y-493446D01*
X1117981Y-491696D01*
X1117108Y-489654D01*
X1116671Y-487321D01*
Y-485279D01*
X1117108Y-483530D01*
X1117981Y-481487D01*
X1119291Y-479738D01*
X1120601Y-478571D01*
X1122348Y-477696D01*
X1123876D01*
X1125623Y-478279D01*
X1126933Y-479446D01*
G01X1134826Y-495196D02*
Y-477696D01*
X1144870Y-495196D01*
Y-477696D01*
G01X1152545Y-495196D02*
Y-477696D01*
X1156911D01*
X1158658Y-478571D01*
X1159968Y-479738D01*
X1161060Y-481487D01*
X1161933Y-483530D01*
X1162151Y-486446D01*
X1161933Y-489363D01*
X1161060Y-491405D01*
X1159968Y-493155D01*
X1158658Y-494321D01*
X1156911Y-495196D01*
X1152545D01*
G01X1082981Y-432696D02*
Y-450196D01*
X1091715D01*
G01X1108778D02*
Y-438530D01*
G01Y-440571D02*
X1107905Y-439405D01*
X1106594Y-438821D01*
X1105066Y-438530D01*
X1103538Y-439113D01*
X1102228Y-440279D01*
X1101354Y-442029D01*
X1100918Y-444363D01*
X1101354Y-446696D01*
X1102228Y-448446D01*
X1103538Y-449613D01*
X1105066Y-450196D01*
X1106594Y-449904D01*
X1107905Y-449030D01*
X1108778Y-447863D01*
G01X1117763Y-455446D02*
X1119073Y-456029D01*
X1120820Y-455446D01*
X1121911Y-454280D01*
X1122785Y-452821D01*
X1124094Y-448155D01*
X1126933Y-438530D01*
G01X1119946D02*
X1124094Y-448155D01*
G01X1136573Y-442321D02*
X1143560D01*
X1142905Y-440279D01*
X1141813Y-439113D01*
X1140285Y-438530D01*
X1138756Y-438821D01*
X1137446Y-439696D01*
X1136573Y-441738D01*
X1136136Y-443488D01*
Y-445238D01*
X1136573Y-446988D01*
X1137665Y-448738D01*
X1138975Y-449904D01*
X1140503Y-450196D01*
X1142031Y-449613D01*
X1143560Y-447863D01*
G01X1154291Y-450196D02*
Y-438530D01*
G01Y-440863D02*
X1155383Y-439696D01*
X1156475Y-438821D01*
X1158003Y-438530D01*
X1159094Y-438821D01*
X1160405Y-439696D01*
G01X1312898Y-495196D02*
X1311151Y-494904D01*
X1309623Y-493738D01*
X1308313Y-491988D01*
X1307439Y-489946D01*
X1307003Y-487613D01*
Y-485279D01*
X1307439Y-482946D01*
X1308313Y-480904D01*
X1309623Y-479155D01*
X1311151Y-477988D01*
X1312898Y-477696D01*
X1314644Y-477988D01*
X1316173Y-479155D01*
X1317483Y-480904D01*
X1318357Y-482946D01*
X1318793Y-485279D01*
Y-487613D01*
X1318357Y-489946D01*
X1317483Y-491988D01*
X1316173Y-493738D01*
X1314644Y-494904D01*
X1312898Y-495196D01*
G01X1314644Y-490529D02*
X1317265Y-495196D01*
G01X1325595Y-477696D02*
Y-490238D01*
X1326468Y-492863D01*
X1328215Y-494613D01*
X1330398Y-495196D01*
X1332581Y-494613D01*
X1334328Y-492863D01*
X1335201Y-490238D01*
Y-477696D01*
G01X1345278D02*
X1350518D01*
G01X1347898D02*
Y-495196D01*
G01X1345278D02*
X1350518D01*
G01X1360376D02*
Y-477696D01*
X1370420Y-495196D01*
Y-477696D01*
G01X1387701Y-479155D02*
X1386391Y-478279D01*
X1384863Y-477696D01*
X1383116D01*
X1381151Y-478571D01*
X1379623Y-480029D01*
X1378531Y-481780D01*
X1377658Y-484696D01*
X1377439Y-487321D01*
X1377876Y-489946D01*
X1378531Y-491696D01*
X1379841Y-493446D01*
X1381370Y-494613D01*
X1382898Y-495196D01*
X1384426D01*
X1385955Y-494613D01*
X1387265Y-493738D01*
X1388357Y-492572D01*
G01X1400398Y-495196D02*
Y-487321D01*
X1396031Y-477696D01*
G01X1404765D02*
X1400398Y-487321D01*
G01X1290595Y-450196D02*
Y-432696D01*
X1294961D01*
X1296708Y-433571D01*
X1298018Y-434738D01*
X1299110Y-436487D01*
X1299983Y-438530D01*
X1300201Y-441446D01*
X1299983Y-444363D01*
X1299110Y-446405D01*
X1298018Y-448155D01*
X1296708Y-449321D01*
X1294961Y-450196D01*
X1290595D01*
G01X1309623Y-442321D02*
X1316610D01*
X1315955Y-440279D01*
X1314863Y-439113D01*
X1313335Y-438530D01*
X1311806Y-438821D01*
X1310496Y-439696D01*
X1309623Y-441738D01*
X1309186Y-443488D01*
Y-445238D01*
X1309623Y-446988D01*
X1310715Y-448738D01*
X1312025Y-449904D01*
X1313553Y-450196D01*
X1315081Y-449613D01*
X1316610Y-447863D01*
G01X1327123Y-448155D02*
X1328215Y-449321D01*
X1329743Y-450196D01*
X1331053D01*
X1332363Y-449613D01*
X1333236Y-448738D01*
X1333673Y-447572D01*
X1333455Y-445821D01*
X1332581Y-444946D01*
X1328651Y-443196D01*
X1327778Y-441154D01*
X1328215Y-439696D01*
X1329088Y-438821D01*
X1330398Y-438530D01*
X1331708Y-438821D01*
X1333018Y-439696D01*
G01X1347898Y-438530D02*
Y-450196D01*
G01Y-433863D02*
X1347461Y-433571D01*
Y-432988D01*
X1347898Y-432696D01*
X1348335Y-432988D01*
Y-433571D01*
X1347898Y-433863D01*
G01X1362341Y-454571D02*
X1363870Y-455738D01*
X1365616Y-456029D01*
X1367144Y-455738D01*
X1368455Y-454280D01*
X1369328Y-452238D01*
Y-438530D01*
G01Y-440863D02*
X1368455Y-439696D01*
X1367144Y-438821D01*
X1365616Y-438530D01*
X1363870Y-439113D01*
X1362778Y-440279D01*
X1361904Y-442321D01*
X1361468Y-444363D01*
X1361686Y-446113D01*
X1362560Y-448155D01*
X1363870Y-449613D01*
X1365616Y-450196D01*
X1366926Y-449904D01*
X1368455Y-448738D01*
X1369328Y-447572D01*
G01X1379186Y-450196D02*
Y-438530D01*
G01Y-441446D02*
X1380060Y-439988D01*
X1381370Y-438821D01*
X1383116Y-438530D01*
X1384644Y-438821D01*
X1385955Y-439988D01*
X1386610Y-442029D01*
Y-450196D01*
G01X1397123Y-442321D02*
X1404110D01*
X1403455Y-440279D01*
X1402363Y-439113D01*
X1400835Y-438530D01*
X1399306Y-438821D01*
X1397996Y-439696D01*
X1397123Y-441738D01*
X1396686Y-443488D01*
Y-445238D01*
X1397123Y-446988D01*
X1398215Y-448738D01*
X1399525Y-449904D01*
X1401053Y-450196D01*
X1402581Y-449613D01*
X1404110Y-447863D01*
G01X1414841Y-450196D02*
Y-438530D01*
G01Y-440863D02*
X1415933Y-439696D01*
X1417025Y-438821D01*
X1418553Y-438530D01*
X1419644Y-438821D01*
X1420955Y-439696D01*
G01X1461598Y-477696D02*
X1459851Y-478279D01*
X1458541Y-479738D01*
X1457668Y-481487D01*
X1457013Y-483821D01*
X1456795Y-486446D01*
X1457013Y-489071D01*
X1457668Y-491405D01*
X1458541Y-493155D01*
X1459851Y-494613D01*
X1461598Y-495196D01*
X1463344Y-494613D01*
X1464655Y-493155D01*
X1465528Y-491405D01*
X1466183Y-489071D01*
X1466401Y-486446D01*
X1466183Y-483821D01*
X1465528Y-481487D01*
X1464655Y-479738D01*
X1463344Y-478279D01*
X1461598Y-477696D01*
G01X1474950Y-487905D02*
X1476478Y-485863D01*
X1477788Y-484696D01*
X1479535Y-484113D01*
X1481063Y-484696D01*
X1482155Y-485863D01*
X1483028Y-487613D01*
X1483246Y-489654D01*
X1483028Y-491405D01*
X1482155Y-493155D01*
X1480844Y-494613D01*
X1479316Y-495196D01*
X1477570Y-494613D01*
X1476041Y-492863D01*
X1475168Y-490238D01*
X1474950Y-487321D01*
X1475386Y-483530D01*
X1476041Y-481487D01*
X1477133Y-479446D01*
X1478661Y-477988D01*
X1480190Y-477696D01*
X1481718Y-478279D01*
X1482810Y-479738D01*
G01X1492668Y-495779D02*
X1500528Y-477696D01*
G01X1514098D02*
X1512351Y-478279D01*
X1511041Y-479738D01*
X1510168Y-481487D01*
X1509513Y-483821D01*
X1509295Y-486446D01*
X1509513Y-489071D01*
X1510168Y-491405D01*
X1511041Y-493155D01*
X1512351Y-494613D01*
X1514098Y-495196D01*
X1515844Y-494613D01*
X1517155Y-493155D01*
X1518028Y-491405D01*
X1518683Y-489071D01*
X1518901Y-486446D01*
X1518683Y-483821D01*
X1518028Y-481487D01*
X1517155Y-479738D01*
X1515844Y-478279D01*
X1514098Y-477696D01*
G01X1527886Y-493155D02*
X1529415Y-494613D01*
X1531161Y-495196D01*
X1532908Y-494613D01*
X1534436Y-492863D01*
X1535528Y-490238D01*
X1535965Y-487613D01*
Y-484405D01*
X1535528Y-481780D01*
X1534436Y-479446D01*
X1533126Y-478279D01*
X1531598Y-477696D01*
X1529851Y-478279D01*
X1528541Y-479446D01*
X1527668Y-481196D01*
X1527231Y-483530D01*
X1527668Y-485571D01*
X1528760Y-487613D01*
X1530070Y-488780D01*
X1531598Y-489071D01*
X1533344Y-488488D01*
X1534655Y-487029D01*
X1535965Y-484405D01*
G01X1545168Y-495779D02*
X1553028Y-477696D01*
G01X1562450Y-480613D02*
X1563760Y-478863D01*
X1565288Y-477988D01*
X1567035Y-477696D01*
X1569218Y-478279D01*
X1570746Y-479738D01*
X1571183Y-481487D01*
X1570965Y-483238D01*
X1570091Y-484696D01*
X1565725Y-487613D01*
X1563760Y-489654D01*
X1562450Y-492572D01*
X1562013Y-495196D01*
X1571183D01*
G01X1584098Y-477696D02*
X1582351Y-478279D01*
X1581041Y-479738D01*
X1580168Y-481487D01*
X1579513Y-483821D01*
X1579295Y-486446D01*
X1579513Y-489071D01*
X1580168Y-491405D01*
X1581041Y-493155D01*
X1582351Y-494613D01*
X1584098Y-495196D01*
X1585844Y-494613D01*
X1587155Y-493155D01*
X1588028Y-491405D01*
X1588683Y-489071D01*
X1588901Y-486446D01*
X1588683Y-483821D01*
X1588028Y-481487D01*
X1587155Y-479738D01*
X1585844Y-478279D01*
X1584098Y-477696D01*
G01X1601598Y-495196D02*
Y-477696D01*
X1598978Y-481196D01*
G01Y-495196D02*
X1604218D01*
G01X1618661D02*
X1619098Y-491405D01*
X1619753Y-488196D01*
X1620626Y-485279D01*
X1621718Y-482071D01*
X1623465Y-477696D01*
X1614731D01*
G01X1509295Y-450196D02*
Y-432696D01*
X1513661D01*
X1515408Y-433571D01*
X1516718Y-434738D01*
X1517810Y-436487D01*
X1518683Y-438530D01*
X1518901Y-441446D01*
X1518683Y-444363D01*
X1517810Y-446405D01*
X1516718Y-448155D01*
X1515408Y-449321D01*
X1513661Y-450196D01*
X1509295D01*
G01X1535528D02*
Y-438530D01*
G01Y-440571D02*
X1534655Y-439405D01*
X1533344Y-438821D01*
X1531816Y-438530D01*
X1530288Y-439113D01*
X1528978Y-440279D01*
X1528104Y-442029D01*
X1527668Y-444363D01*
X1528104Y-446696D01*
X1528978Y-448446D01*
X1530288Y-449613D01*
X1531816Y-450196D01*
X1533344Y-449904D01*
X1534655Y-449030D01*
X1535528Y-447863D01*
G01X1549098Y-432696D02*
Y-450196D01*
G01X1546041Y-438530D02*
X1552155D01*
G01X1563323Y-442321D02*
X1570310D01*
X1569655Y-440279D01*
X1568563Y-439113D01*
X1567035Y-438530D01*
X1565506Y-438821D01*
X1564196Y-439696D01*
X1563323Y-441738D01*
X1562886Y-443488D01*
Y-445238D01*
X1563323Y-446988D01*
X1564415Y-448738D01*
X1565725Y-449904D01*
X1567253Y-450196D01*
X1568781Y-449613D01*
X1570310Y-447863D01*
M02*
